FILE_TYPE = MACRO_DRAWING;
SET COLOR_WIRE YELLOW;
SET COLOR_PROP MONO;
SET COLOR_DOT WHITE;
SET COLOR_ARC YELLOW;
SET COLOR_BODY GREEN;
SET COLOR_NOTE MONO;
SET PROP_DISPLAY VALUE;
SET PAGE_NUMBER P78;
FORCEADD GND..1
(-2675 625);
FORCEPROP 3 LASTPIN (-2675 675) SIG_NAME GND\g
J 0
(-2665 685);
DISPLAY 0.659574 (-2665 685);
PAINT MONO (-2665 685);
DISPLAY INVISIBLE (-2665 685);
FORCEPROP 1 LAST VOLTAGE 0.0V
J 0
(-2720 582);
DISPLAY 0.340426 (-2720 582);
PAINT SKYBLUE (-2720 582);
DISPLAY INVISIBLE (-2720 582);
FORCEPROP 1 LAST SIZE 1B
J 0
(-2600 575);
DISPLAY 1.787234 (-2600 575);
PAINT GREEN (-2600 575);
DISPLAY INVISIBLE (-2600 575);
FORCEPROP 2 LAST CDS_LIB mstr_symbols
J 0
(-2675 625);
PAINT ORANGE (-2675 625);
DISPLAY INVISIBLE (-2675 625);
FORCEPROP 2 LAST BOM_COST MEM
J 0
(-2675 630);
PAINT ORANGE (-2675 630);
DISPLAY INVISIBLE (-2675 630);
FORCEPROP 1 LAST BODY_TYPE PLUMBING
J 0
(-2720 582);
DISPLAY 0.340426 (-2720 582);
PAINT GREEN (-2720 582);
DISPLAY INVISIBLE (-2720 582);
FORCEPROP 1 LAST PATH I1
J 0
(-2600 625);
DISPLAY 0.872340 (-2600 625);
PAINT AQUA (-2600 625);
DISPLAY INVISIBLE (-2600 625);
FORCEPROP 2 LAST ROOM DDR4_GH_G
J 0
(-2675 630);
PAINT ORANGE (-2675 630);
DISPLAY INVISIBLE (-2675 630);
FORCEPROP 1 LAST HDL_POWER GND
J 0
(-2675 775);
DISPLAY 1.404255 (-2675 775);
PAINT GREEN (-2675 775);
DISPLAY INVISIBLE (-2675 775);
FORCEADD OFFPAGE..6
(-2025 1225);
FORCEPROP 2 LAST $XR0 77 
J 0
(-2274 1225);
DISPLAY 0.638298 (-2274 1225);
PAINT MONO (-2274 1225);
FORCEPROP 2 LAST $XR1 79 
J 0
(-2364 1225);
DISPLAY 0.638298 (-2364 1225);
PAINT MONO (-2364 1225);
FORCEPROP 2 LAST $XR2 80 
J 0
(-2454 1225);
DISPLAY 0.638298 (-2454 1225);
PAINT MONO (-2454 1225);
FORCEPROP 2 LAST $XR3 81 
J 0
(-2544 1225);
DISPLAY 0.638298 (-2544 1225);
PAINT MONO (-2544 1225);
FORCEPROP 2 LAST $XR4 82 
J 0
(-2634 1225);
DISPLAY 0.638298 (-2634 1225);
PAINT MONO (-2634 1225);
FORCEPROP 2 LAST $XR5 99 
J 0
(-2724 1225);
DISPLAY 0.638298 (-2724 1225);
PAINT MONO (-2724 1225);
FORCEPROP 2 LASTPIN (-1975 1225) SIG_NAME SMB_DDR_GHJ_VPP_SDA
J 0
(-1935 1235);
DISPLAY 0.617021 (-1935 1235);
PAINT ORANGE (-1935 1235);
FORCEPROP 2 LAST CDS_LIB mstr_standard
J 0
(-2025 1225);
DISPLAY 0.787234 (-2025 1225);
PAINT MONO (-2025 1225);
DISPLAY INVISIBLE (-2025 1225);
FORCEPROP 1 LAST OFFPAGE TRUE
J 0
(-1700 1100);
DISPLAY 0.936170 (-1700 1100);
PAINT GREEN (-1700 1100);
DISPLAY INVISIBLE (-1700 1100);
FORCEPROP 1 LAST COMMENT_BODY TRUE
J 0
(-1925 1150);
DISPLAY 0.936170 (-1925 1150);
PAINT GREEN (-1925 1150);
DISPLAY INVISIBLE (-1925 1150);
FORCEPROP 2 LAST PATH I10
J 0
(-2250 1275);
DISPLAY 1.021277 (-2250 1275);
PAINT ORANGE (-2250 1275);
DISPLAY INVISIBLE (-2250 1275);
FORCEADD TAP..6
R 2
(125 2925);
FORCEPROP 3 LASTPIN (75 2925) SIG_NAME M_G_DQ<37>
J 0
(85 2935);
DISPLAY 0.659574 (85 2935);
PAINT MONO (85 2935);
DISPLAY INVISIBLE (85 2935);
FORCEPROP 1 LASTPIN (75 2925) BN 37
J 2
(125 2935);
DISPLAY 0.617021 (125 2935);
PAINT PINK (125 2935);
FORCEPROP 2 LAST CDS_LIB mstr_standard
J 2
(125 2925);
DISPLAY 0.787234 (125 2925);
PAINT MONO (125 2925);
DISPLAY INVISIBLE (125 2925);
FORCEPROP 1 LAST BODY_TYPE PLUMBING
J 2
(125 2875);
DISPLAY 1.234043 (125 2875);
PAINT GREEN (125 2875);
DISPLAY INVISIBLE (125 2875);
FORCEPROP 1 LAST HDL_TAP TRUE
J 2
(-200 2800);
DISPLAY 1.234043 (-200 2800);
PAINT GREEN (-200 2800);
DISPLAY INVISIBLE (-200 2800);
FORCEPROP 1 LAST PATH I100
J 2
(127 2925);
DISPLAY 0.872340 (127 2925);
PAINT GREEN (127 2925);
DISPLAY INVISIBLE (127 2925);
FORCEADD TAP..6
R 2
(125 3125);
FORCEPROP 3 LASTPIN (75 3125) SIG_NAME M_G_DQ<41>
J 0
(85 3135);
DISPLAY 0.659574 (85 3135);
PAINT MONO (85 3135);
DISPLAY INVISIBLE (85 3135);
FORCEPROP 1 LASTPIN (75 3125) BN 41
J 2
(125 3135);
DISPLAY 0.617021 (125 3135);
PAINT PINK (125 3135);
FORCEPROP 2 LAST CDS_LIB mstr_standard
J 2
(125 3125);
DISPLAY 0.787234 (125 3125);
PAINT MONO (125 3125);
DISPLAY INVISIBLE (125 3125);
FORCEPROP 1 LAST BODY_TYPE PLUMBING
J 2
(125 3075);
DISPLAY 1.234043 (125 3075);
PAINT GREEN (125 3075);
DISPLAY INVISIBLE (125 3075);
FORCEPROP 1 LAST HDL_TAP TRUE
J 2
(-200 3000);
DISPLAY 1.234043 (-200 3000);
PAINT GREEN (-200 3000);
DISPLAY INVISIBLE (-200 3000);
FORCEPROP 1 LAST PATH I101
J 2
(127 3125);
DISPLAY 0.872340 (127 3125);
PAINT GREEN (127 3125);
DISPLAY INVISIBLE (127 3125);
FORCEADD TAP..6
R 2
(125 3025);
FORCEPROP 3 LASTPIN (75 3025) SIG_NAME M_G_DQ<39>
J 0
(85 3035);
DISPLAY 0.659574 (85 3035);
PAINT MONO (85 3035);
DISPLAY INVISIBLE (85 3035);
FORCEPROP 1 LASTPIN (75 3025) BN 39
J 2
(125 3035);
DISPLAY 0.617021 (125 3035);
PAINT PINK (125 3035);
FORCEPROP 2 LAST CDS_LIB mstr_standard
J 2
(125 3025);
DISPLAY 0.787234 (125 3025);
PAINT MONO (125 3025);
DISPLAY INVISIBLE (125 3025);
FORCEPROP 1 LAST BODY_TYPE PLUMBING
J 2
(125 2975);
DISPLAY 1.234043 (125 2975);
PAINT GREEN (125 2975);
DISPLAY INVISIBLE (125 2975);
FORCEPROP 1 LAST HDL_TAP TRUE
J 2
(-200 2900);
DISPLAY 1.234043 (-200 2900);
PAINT GREEN (-200 2900);
DISPLAY INVISIBLE (-200 2900);
FORCEPROP 1 LAST PATH I102
J 2
(127 3025);
DISPLAY 0.872340 (127 3025);
PAINT GREEN (127 3025);
DISPLAY INVISIBLE (127 3025);
FORCEADD TAP..6
R 2
(125 3075);
FORCEPROP 3 LASTPIN (75 3075) SIG_NAME M_G_DQ<40>
J 0
(85 3085);
DISPLAY 0.659574 (85 3085);
PAINT MONO (85 3085);
DISPLAY INVISIBLE (85 3085);
FORCEPROP 1 LASTPIN (75 3075) BN 40
J 2
(125 3085);
DISPLAY 0.617021 (125 3085);
PAINT PINK (125 3085);
FORCEPROP 2 LAST CDS_LIB mstr_standard
J 2
(125 3075);
DISPLAY 0.787234 (125 3075);
PAINT MONO (125 3075);
DISPLAY INVISIBLE (125 3075);
FORCEPROP 1 LAST BODY_TYPE PLUMBING
J 2
(125 3025);
DISPLAY 1.234043 (125 3025);
PAINT GREEN (125 3025);
DISPLAY INVISIBLE (125 3025);
FORCEPROP 1 LAST HDL_TAP TRUE
J 2
(-200 2950);
DISPLAY 1.234043 (-200 2950);
PAINT GREEN (-200 2950);
DISPLAY INVISIBLE (-200 2950);
FORCEPROP 1 LAST PATH I103
J 2
(127 3075);
DISPLAY 0.872340 (127 3075);
PAINT GREEN (127 3075);
DISPLAY INVISIBLE (127 3075);
FORCEADD TAP..6
R 2
(125 3175);
FORCEPROP 3 LASTPIN (75 3175) SIG_NAME M_G_DQ<42>
J 0
(85 3185);
DISPLAY 0.659574 (85 3185);
PAINT MONO (85 3185);
DISPLAY INVISIBLE (85 3185);
FORCEPROP 1 LASTPIN (75 3175) BN 42
J 2
(125 3185);
DISPLAY 0.617021 (125 3185);
PAINT PINK (125 3185);
FORCEPROP 2 LAST CDS_LIB mstr_standard
J 2
(125 3175);
DISPLAY 0.787234 (125 3175);
PAINT MONO (125 3175);
DISPLAY INVISIBLE (125 3175);
FORCEPROP 1 LAST BODY_TYPE PLUMBING
J 2
(125 3125);
DISPLAY 1.234043 (125 3125);
PAINT GREEN (125 3125);
DISPLAY INVISIBLE (125 3125);
FORCEPROP 1 LAST HDL_TAP TRUE
J 2
(-200 3050);
DISPLAY 1.234043 (-200 3050);
PAINT GREEN (-200 3050);
DISPLAY INVISIBLE (-200 3050);
FORCEPROP 1 LAST PATH I104
J 2
(127 3175);
DISPLAY 0.872340 (127 3175);
PAINT GREEN (127 3175);
DISPLAY INVISIBLE (127 3175);
FORCEADD TAP..6
R 2
(125 3225);
FORCEPROP 3 LASTPIN (75 3225) SIG_NAME M_G_DQ<43>
J 0
(85 3235);
DISPLAY 0.659574 (85 3235);
PAINT MONO (85 3235);
DISPLAY INVISIBLE (85 3235);
FORCEPROP 1 LASTPIN (75 3225) BN 43
J 2
(125 3235);
DISPLAY 0.617021 (125 3235);
PAINT PINK (125 3235);
FORCEPROP 2 LAST CDS_LIB mstr_standard
J 2
(125 3225);
DISPLAY 0.787234 (125 3225);
PAINT MONO (125 3225);
DISPLAY INVISIBLE (125 3225);
FORCEPROP 1 LAST BODY_TYPE PLUMBING
J 2
(125 3175);
DISPLAY 1.234043 (125 3175);
PAINT GREEN (125 3175);
DISPLAY INVISIBLE (125 3175);
FORCEPROP 1 LAST HDL_TAP TRUE
J 2
(-200 3100);
DISPLAY 1.234043 (-200 3100);
PAINT GREEN (-200 3100);
DISPLAY INVISIBLE (-200 3100);
FORCEPROP 1 LAST PATH I105
J 2
(127 3225);
DISPLAY 0.872340 (127 3225);
PAINT GREEN (127 3225);
DISPLAY INVISIBLE (127 3225);
FORCEADD TAP..6
R 2
(125 3275);
FORCEPROP 3 LASTPIN (75 3275) SIG_NAME M_G_DQ<44>
J 0
(85 3285);
DISPLAY 0.659574 (85 3285);
PAINT MONO (85 3285);
DISPLAY INVISIBLE (85 3285);
FORCEPROP 1 LASTPIN (75 3275) BN 44
J 2
(125 3285);
DISPLAY 0.617021 (125 3285);
PAINT PINK (125 3285);
FORCEPROP 2 LAST CDS_LIB mstr_standard
J 2
(125 3275);
DISPLAY 0.787234 (125 3275);
PAINT MONO (125 3275);
DISPLAY INVISIBLE (125 3275);
FORCEPROP 1 LAST BODY_TYPE PLUMBING
J 2
(125 3225);
DISPLAY 1.234043 (125 3225);
PAINT GREEN (125 3225);
DISPLAY INVISIBLE (125 3225);
FORCEPROP 1 LAST HDL_TAP TRUE
J 2
(-200 3150);
DISPLAY 1.234043 (-200 3150);
PAINT GREEN (-200 3150);
DISPLAY INVISIBLE (-200 3150);
FORCEPROP 1 LAST PATH I106
J 2
(127 3275);
DISPLAY 0.872340 (127 3275);
PAINT GREEN (127 3275);
DISPLAY INVISIBLE (127 3275);
FORCEADD TAP..6
R 2
(125 3325);
FORCEPROP 3 LASTPIN (75 3325) SIG_NAME M_G_DQ<45>
J 0
(85 3335);
DISPLAY 0.659574 (85 3335);
PAINT MONO (85 3335);
DISPLAY INVISIBLE (85 3335);
FORCEPROP 1 LASTPIN (75 3325) BN 45
J 2
(125 3335);
DISPLAY 0.617021 (125 3335);
PAINT PINK (125 3335);
FORCEPROP 2 LAST CDS_LIB mstr_standard
J 2
(125 3325);
DISPLAY 0.787234 (125 3325);
PAINT MONO (125 3325);
DISPLAY INVISIBLE (125 3325);
FORCEPROP 1 LAST BODY_TYPE PLUMBING
J 2
(125 3275);
DISPLAY 1.234043 (125 3275);
PAINT GREEN (125 3275);
DISPLAY INVISIBLE (125 3275);
FORCEPROP 1 LAST HDL_TAP TRUE
J 2
(-200 3200);
DISPLAY 1.234043 (-200 3200);
PAINT GREEN (-200 3200);
DISPLAY INVISIBLE (-200 3200);
FORCEPROP 1 LAST PATH I107
J 2
(127 3325);
DISPLAY 0.872340 (127 3325);
PAINT GREEN (127 3325);
DISPLAY INVISIBLE (127 3325);
FORCEADD TAP..6
R 2
(125 3375);
FORCEPROP 3 LASTPIN (75 3375) SIG_NAME M_G_DQ<46>
J 0
(85 3385);
DISPLAY 0.659574 (85 3385);
PAINT MONO (85 3385);
DISPLAY INVISIBLE (85 3385);
FORCEPROP 1 LASTPIN (75 3375) BN 46
J 2
(125 3385);
DISPLAY 0.617021 (125 3385);
PAINT PINK (125 3385);
FORCEPROP 2 LAST CDS_LIB mstr_standard
J 2
(125 3375);
DISPLAY 0.787234 (125 3375);
PAINT MONO (125 3375);
DISPLAY INVISIBLE (125 3375);
FORCEPROP 1 LAST BODY_TYPE PLUMBING
J 2
(125 3325);
DISPLAY 1.234043 (125 3325);
PAINT GREEN (125 3325);
DISPLAY INVISIBLE (125 3325);
FORCEPROP 1 LAST HDL_TAP TRUE
J 2
(-200 3250);
DISPLAY 1.234043 (-200 3250);
PAINT GREEN (-200 3250);
DISPLAY INVISIBLE (-200 3250);
FORCEPROP 1 LAST PATH I108
J 2
(127 3375);
DISPLAY 0.872340 (127 3375);
PAINT GREEN (127 3375);
DISPLAY INVISIBLE (127 3375);
FORCEADD TAP..6
R 2
(125 3475);
FORCEPROP 3 LASTPIN (75 3475) SIG_NAME M_G_DQ<48>
J 0
(85 3485);
DISPLAY 0.659574 (85 3485);
PAINT MONO (85 3485);
DISPLAY INVISIBLE (85 3485);
FORCEPROP 1 LASTPIN (75 3475) BN 48
J 2
(125 3485);
DISPLAY 0.617021 (125 3485);
PAINT PINK (125 3485);
FORCEPROP 2 LAST CDS_LIB mstr_standard
J 2
(125 3475);
DISPLAY 0.787234 (125 3475);
PAINT MONO (125 3475);
DISPLAY INVISIBLE (125 3475);
FORCEPROP 1 LAST BODY_TYPE PLUMBING
J 2
(125 3425);
DISPLAY 1.234043 (125 3425);
PAINT GREEN (125 3425);
DISPLAY INVISIBLE (125 3425);
FORCEPROP 1 LAST HDL_TAP TRUE
J 2
(-200 3350);
DISPLAY 1.234043 (-200 3350);
PAINT GREEN (-200 3350);
DISPLAY INVISIBLE (-200 3350);
FORCEPROP 1 LAST PATH I109
J 2
(127 3475);
DISPLAY 0.872340 (127 3475);
PAINT GREEN (127 3475);
DISPLAY INVISIBLE (127 3475);
FORCEADD OFFPAGE..1
(-2175 1525);
FORCEPROP 2 LAST $XR0 57 
J 0
(-2426 1525);
DISPLAY 0.638298 (-2426 1525);
PAINT MONO (-2426 1525);
FORCEPROP 2 LAST $XR1 77 
J 0
(-2516 1525);
DISPLAY 0.638298 (-2516 1525);
PAINT MONO (-2516 1525);
FORCEPROP 2 LAST CDS_LIB mstr_standard
J 0
(-2175 1525);
DISPLAY 0.787234 (-2175 1525);
PAINT MONO (-2175 1525);
DISPLAY INVISIBLE (-2175 1525);
FORCEPROP 1 LAST OFFPAGE TRUE
J 0
(-1850 1400);
DISPLAY 0.936170 (-1850 1400);
PAINT GREEN (-1850 1400);
DISPLAY INVISIBLE (-1850 1400);
FORCEPROP 1 LAST COMMENT_BODY TRUE
J 0
(-2050 1425);
DISPLAY 0.936170 (-2050 1425);
PAINT GREEN (-2050 1425);
DISPLAY INVISIBLE (-2050 1425);
FORCEPROP 2 LAST PATH I11
J 0
(-2425 1575);
DISPLAY 1.021277 (-2425 1575);
PAINT ORANGE (-2425 1575);
DISPLAY INVISIBLE (-2425 1575);
FORCEADD TAP..6
R 2
(125 3425);
FORCEPROP 3 LASTPIN (75 3425) SIG_NAME M_G_DQ<47>
J 0
(85 3435);
DISPLAY 0.659574 (85 3435);
PAINT MONO (85 3435);
DISPLAY INVISIBLE (85 3435);
FORCEPROP 1 LASTPIN (75 3425) BN 47
J 2
(125 3435);
DISPLAY 0.617021 (125 3435);
PAINT PINK (125 3435);
FORCEPROP 2 LAST CDS_LIB mstr_standard
J 2
(125 3425);
DISPLAY 0.787234 (125 3425);
PAINT MONO (125 3425);
DISPLAY INVISIBLE (125 3425);
FORCEPROP 1 LAST BODY_TYPE PLUMBING
J 2
(125 3375);
DISPLAY 1.234043 (125 3375);
PAINT GREEN (125 3375);
DISPLAY INVISIBLE (125 3375);
FORCEPROP 1 LAST HDL_TAP TRUE
J 2
(-200 3300);
DISPLAY 1.234043 (-200 3300);
PAINT GREEN (-200 3300);
DISPLAY INVISIBLE (-200 3300);
FORCEPROP 1 LAST PATH I110
J 2
(127 3425);
DISPLAY 0.872340 (127 3425);
PAINT GREEN (127 3425);
DISPLAY INVISIBLE (127 3425);
FORCEADD TAP..6
R 2
(125 3525);
FORCEPROP 3 LASTPIN (75 3525) SIG_NAME M_G_DQ<49>
J 0
(85 3535);
DISPLAY 0.659574 (85 3535);
PAINT MONO (85 3535);
DISPLAY INVISIBLE (85 3535);
FORCEPROP 1 LASTPIN (75 3525) BN 49
J 2
(125 3535);
DISPLAY 0.617021 (125 3535);
PAINT PINK (125 3535);
FORCEPROP 2 LAST CDS_LIB mstr_standard
J 2
(125 3525);
DISPLAY 0.787234 (125 3525);
PAINT MONO (125 3525);
DISPLAY INVISIBLE (125 3525);
FORCEPROP 1 LAST BODY_TYPE PLUMBING
J 2
(125 3475);
DISPLAY 1.234043 (125 3475);
PAINT GREEN (125 3475);
DISPLAY INVISIBLE (125 3475);
FORCEPROP 1 LAST HDL_TAP TRUE
J 2
(-200 3400);
DISPLAY 1.234043 (-200 3400);
PAINT GREEN (-200 3400);
DISPLAY INVISIBLE (-200 3400);
FORCEPROP 1 LAST PATH I111
J 2
(127 3525);
DISPLAY 0.872340 (127 3525);
PAINT GREEN (127 3525);
DISPLAY INVISIBLE (127 3525);
FORCEADD TAP..6
R 2
(125 3575);
FORCEPROP 3 LASTPIN (75 3575) SIG_NAME M_G_DQ<50>
J 0
(85 3585);
DISPLAY 0.659574 (85 3585);
PAINT MONO (85 3585);
DISPLAY INVISIBLE (85 3585);
FORCEPROP 1 LASTPIN (75 3575) BN 50
J 2
(125 3585);
DISPLAY 0.617021 (125 3585);
PAINT PINK (125 3585);
FORCEPROP 2 LAST CDS_LIB mstr_standard
J 2
(125 3575);
DISPLAY 0.787234 (125 3575);
PAINT MONO (125 3575);
DISPLAY INVISIBLE (125 3575);
FORCEPROP 1 LAST BODY_TYPE PLUMBING
J 2
(125 3525);
DISPLAY 1.234043 (125 3525);
PAINT GREEN (125 3525);
DISPLAY INVISIBLE (125 3525);
FORCEPROP 1 LAST HDL_TAP TRUE
J 2
(-200 3450);
DISPLAY 1.234043 (-200 3450);
PAINT GREEN (-200 3450);
DISPLAY INVISIBLE (-200 3450);
FORCEPROP 1 LAST PATH I112
J 2
(127 3575);
DISPLAY 0.872340 (127 3575);
PAINT GREEN (127 3575);
DISPLAY INVISIBLE (127 3575);
FORCEADD TAP..6
R 2
(125 3625);
FORCEPROP 3 LASTPIN (75 3625) SIG_NAME M_G_DQ<51>
J 0
(85 3635);
DISPLAY 0.659574 (85 3635);
PAINT MONO (85 3635);
DISPLAY INVISIBLE (85 3635);
FORCEPROP 1 LASTPIN (75 3625) BN 51
J 2
(125 3635);
DISPLAY 0.617021 (125 3635);
PAINT PINK (125 3635);
FORCEPROP 2 LAST CDS_LIB mstr_standard
J 2
(125 3625);
DISPLAY 0.787234 (125 3625);
PAINT MONO (125 3625);
DISPLAY INVISIBLE (125 3625);
FORCEPROP 1 LAST BODY_TYPE PLUMBING
J 2
(125 3575);
DISPLAY 1.234043 (125 3575);
PAINT GREEN (125 3575);
DISPLAY INVISIBLE (125 3575);
FORCEPROP 1 LAST HDL_TAP TRUE
J 2
(-200 3500);
DISPLAY 1.234043 (-200 3500);
PAINT GREEN (-200 3500);
DISPLAY INVISIBLE (-200 3500);
FORCEPROP 1 LAST PATH I113
J 2
(127 3625);
DISPLAY 0.872340 (127 3625);
PAINT GREEN (127 3625);
DISPLAY INVISIBLE (127 3625);
FORCEADD TAP..6
R 2
(125 3775);
FORCEPROP 3 LASTPIN (75 3775) SIG_NAME M_G_DQ<54>
J 0
(85 3785);
DISPLAY 0.659574 (85 3785);
PAINT MONO (85 3785);
DISPLAY INVISIBLE (85 3785);
FORCEPROP 1 LASTPIN (75 3775) BN 54
J 2
(125 3785);
DISPLAY 0.617021 (125 3785);
PAINT PINK (125 3785);
FORCEPROP 2 LAST CDS_LIB mstr_standard
J 2
(125 3775);
DISPLAY 0.787234 (125 3775);
PAINT MONO (125 3775);
DISPLAY INVISIBLE (125 3775);
FORCEPROP 1 LAST BODY_TYPE PLUMBING
J 2
(125 3725);
DISPLAY 1.234043 (125 3725);
PAINT GREEN (125 3725);
DISPLAY INVISIBLE (125 3725);
FORCEPROP 1 LAST HDL_TAP TRUE
J 2
(-200 3650);
DISPLAY 1.234043 (-200 3650);
PAINT GREEN (-200 3650);
DISPLAY INVISIBLE (-200 3650);
FORCEPROP 1 LAST PATH I114
J 2
(127 3775);
DISPLAY 0.872340 (127 3775);
PAINT GREEN (127 3775);
DISPLAY INVISIBLE (127 3775);
FORCEADD TAP..6
R 2
(125 3725);
FORCEPROP 3 LASTPIN (75 3725) SIG_NAME M_G_DQ<53>
J 0
(85 3735);
DISPLAY 0.659574 (85 3735);
PAINT MONO (85 3735);
DISPLAY INVISIBLE (85 3735);
FORCEPROP 1 LASTPIN (75 3725) BN 53
J 2
(125 3735);
DISPLAY 0.617021 (125 3735);
PAINT PINK (125 3735);
FORCEPROP 2 LAST CDS_LIB mstr_standard
J 2
(125 3725);
DISPLAY 0.787234 (125 3725);
PAINT MONO (125 3725);
DISPLAY INVISIBLE (125 3725);
FORCEPROP 1 LAST BODY_TYPE PLUMBING
J 2
(125 3675);
DISPLAY 1.234043 (125 3675);
PAINT GREEN (125 3675);
DISPLAY INVISIBLE (125 3675);
FORCEPROP 1 LAST HDL_TAP TRUE
J 2
(-200 3600);
DISPLAY 1.234043 (-200 3600);
PAINT GREEN (-200 3600);
DISPLAY INVISIBLE (-200 3600);
FORCEPROP 1 LAST PATH I115
J 2
(127 3725);
DISPLAY 0.872340 (127 3725);
PAINT GREEN (127 3725);
DISPLAY INVISIBLE (127 3725);
FORCEADD TAP..6
R 2
(125 3675);
FORCEPROP 3 LASTPIN (75 3675) SIG_NAME M_G_DQ<52>
J 0
(85 3685);
DISPLAY 0.659574 (85 3685);
PAINT MONO (85 3685);
DISPLAY INVISIBLE (85 3685);
FORCEPROP 1 LASTPIN (75 3675) BN 52
J 2
(125 3685);
DISPLAY 0.617021 (125 3685);
PAINT PINK (125 3685);
FORCEPROP 2 LAST CDS_LIB mstr_standard
J 2
(125 3675);
DISPLAY 0.787234 (125 3675);
PAINT MONO (125 3675);
DISPLAY INVISIBLE (125 3675);
FORCEPROP 1 LAST BODY_TYPE PLUMBING
J 2
(125 3625);
DISPLAY 1.234043 (125 3625);
PAINT GREEN (125 3625);
DISPLAY INVISIBLE (125 3625);
FORCEPROP 1 LAST HDL_TAP TRUE
J 2
(-200 3550);
DISPLAY 1.234043 (-200 3550);
PAINT GREEN (-200 3550);
DISPLAY INVISIBLE (-200 3550);
FORCEPROP 1 LAST PATH I116
J 2
(127 3675);
DISPLAY 0.872340 (127 3675);
PAINT GREEN (127 3675);
DISPLAY INVISIBLE (127 3675);
FORCEADD TAP..6
R 2
(125 3825);
FORCEPROP 3 LASTPIN (75 3825) SIG_NAME M_G_DQ<55>
J 0
(85 3835);
DISPLAY 0.659574 (85 3835);
PAINT MONO (85 3835);
DISPLAY INVISIBLE (85 3835);
FORCEPROP 1 LASTPIN (75 3825) BN 55
J 2
(125 3835);
DISPLAY 0.617021 (125 3835);
PAINT PINK (125 3835);
FORCEPROP 2 LAST CDS_LIB mstr_standard
J 2
(125 3825);
DISPLAY 0.787234 (125 3825);
PAINT MONO (125 3825);
DISPLAY INVISIBLE (125 3825);
FORCEPROP 1 LAST BODY_TYPE PLUMBING
J 2
(125 3775);
DISPLAY 1.234043 (125 3775);
PAINT GREEN (125 3775);
DISPLAY INVISIBLE (125 3775);
FORCEPROP 1 LAST HDL_TAP TRUE
J 2
(-200 3700);
DISPLAY 1.234043 (-200 3700);
PAINT GREEN (-200 3700);
DISPLAY INVISIBLE (-200 3700);
FORCEPROP 1 LAST PATH I117
J 2
(127 3825);
DISPLAY 0.872340 (127 3825);
PAINT GREEN (127 3825);
DISPLAY INVISIBLE (127 3825);
FORCEADD TAP..6
R 2
(125 3875);
FORCEPROP 3 LASTPIN (75 3875) SIG_NAME M_G_DQ<56>
J 0
(85 3885);
DISPLAY 0.659574 (85 3885);
PAINT MONO (85 3885);
DISPLAY INVISIBLE (85 3885);
FORCEPROP 1 LASTPIN (75 3875) BN 56
J 2
(125 3885);
DISPLAY 0.617021 (125 3885);
PAINT PINK (125 3885);
FORCEPROP 2 LAST CDS_LIB mstr_standard
J 2
(125 3875);
DISPLAY 0.787234 (125 3875);
PAINT MONO (125 3875);
DISPLAY INVISIBLE (125 3875);
FORCEPROP 1 LAST BODY_TYPE PLUMBING
J 2
(125 3825);
DISPLAY 1.234043 (125 3825);
PAINT GREEN (125 3825);
DISPLAY INVISIBLE (125 3825);
FORCEPROP 1 LAST HDL_TAP TRUE
J 2
(-200 3750);
DISPLAY 1.234043 (-200 3750);
PAINT GREEN (-200 3750);
DISPLAY INVISIBLE (-200 3750);
FORCEPROP 1 LAST PATH I118
J 2
(127 3875);
DISPLAY 0.872340 (127 3875);
PAINT GREEN (127 3875);
DISPLAY INVISIBLE (127 3875);
FORCEADD PVPP_GHJ..1
(750 2750);
FORCEPROP 3 LASTPIN (750 2700) SIG_NAME PVPP_GHJ\g
J 0
(760 2710);
DISPLAY 0.659574 (760 2710);
PAINT MONO (760 2710);
DISPLAY INVISIBLE (760 2710);
FORCEPROP 1 LAST VOLTAGE 2.5V
J 0
(705 2707);
DISPLAY 0.340426 (705 2707);
PAINT SKYBLUE (705 2707);
DISPLAY INVISIBLE (705 2707);
FORCEPROP 0 LAST BOM_COST MEM
J 0
(750 2850);
PAINT ORANGE (750 2850);
DISPLAY INVISIBLE (750 2850);
FORCEPROP 2 LAST CDS_LIB mstr_symbols
J 0
(750 2750);
PAINT ORANGE (750 2750);
DISPLAY INVISIBLE (750 2750);
FORCEPROP 1 LAST BODY_TYPE PLUMBING
J 0
(705 2707);
DISPLAY 0.340426 (705 2707);
PAINT GREEN (705 2707);
DISPLAY INVISIBLE (705 2707);
FORCEPROP 1 LAST PATH I119
J 0
(800 2775);
DISPLAY 0.872340 (800 2775);
PAINT AQUA (800 2775);
DISPLAY INVISIBLE (800 2775);
FORCEPROP 2 LAST ROOM DDR4_GH_G
J 0
(750 2850);
PAINT ORANGE (750 2850);
DISPLAY INVISIBLE (750 2850);
FORCEPROP 1 LAST HDL_POWER PVPP_GHJ
J 1
(750 2800);
DISPLAY 0.872340 (750 2800);
PAINT GREEN (750 2800);
DISPLAY INVISIBLE (750 2800);
FORCEADD TAP..6
(-1375 1825);
FORCEPROP 3 LASTPIN (-1325 1825) SIG_NAME M_G_ECC<0>
J 0
(-1315 1835);
DISPLAY 0.659574 (-1315 1835);
PAINT MONO (-1315 1835);
DISPLAY INVISIBLE (-1315 1835);
FORCEPROP 1 LASTPIN (-1325 1825) BN 0
J 0
(-1375 1835);
DISPLAY 0.617021 (-1375 1835);
PAINT PINK (-1375 1835);
FORCEPROP 2 LAST CDS_LIB mstr_standard
J 0
(-1375 1825);
DISPLAY 0.787234 (-1375 1825);
PAINT MONO (-1375 1825);
DISPLAY INVISIBLE (-1375 1825);
FORCEPROP 1 LAST BODY_TYPE PLUMBING
J 0
(-1375 1775);
DISPLAY 1.234043 (-1375 1775);
PAINT GREEN (-1375 1775);
DISPLAY INVISIBLE (-1375 1775);
FORCEPROP 1 LAST HDL_TAP TRUE
J 0
(-1050 1700);
DISPLAY 1.234043 (-1050 1700);
PAINT GREEN (-1050 1700);
DISPLAY INVISIBLE (-1050 1700);
FORCEPROP 1 LAST PATH I12
J 0
(-1377 1825);
DISPLAY 0.872340 (-1377 1825);
PAINT GREEN (-1377 1825);
DISPLAY INVISIBLE (-1377 1825);
FORCEADD SCONN288_H44441003..2
(1750 4000);
FORCEPROP 1 LAST LOCATION J9T1
J 0
(1350 5100);
DISPLAY 0.617021 (1350 5100);
PAINT AQUA (1350 5100);
FORCEPROP 1 LAST PART_NUMBER H44441-003
J 0
(1350 2900);
DISPLAY 0.617021 (1350 2900);
PAINT BLUE (1350 2900);
FORCEPROP 1 LAST MATERIAL SCONN
J 0
(1350 5050);
DISPLAY 0.617021 (1350 5050);
PAINT SKYBLUE (1350 5050);
FORCEPROP 2 LASTPIN (2200 4850) $PN 51
J 0
(2210 4860);
DISPLAY 0.617021 (2210 4860);
PAINT ORANGE (2210 4860);
FORCEPROP 2 LASTPIN (2200 4800) $PN 52
J 0
(2210 4810);
DISPLAY 0.617021 (2210 4810);
PAINT ORANGE (2210 4810);
FORCEPROP 2 LASTPIN (2200 4750) $PN 132
J 0
(2210 4760);
DISPLAY 0.617021 (2210 4760);
PAINT ORANGE (2210 4760);
FORCEPROP 2 LASTPIN (2200 4700) $PN 133
J 0
(2210 4710);
DISPLAY 0.617021 (2210 4710);
PAINT ORANGE (2210 4710);
FORCEPROP 2 LASTPIN (2200 4650) $PN 121
J 0
(2210 4660);
DISPLAY 0.617021 (2210 4660);
PAINT ORANGE (2210 4660);
FORCEPROP 2 LASTPIN (2200 4600) $PN 122
J 0
(2210 4610);
DISPLAY 0.617021 (2210 4610);
PAINT ORANGE (2210 4610);
FORCEPROP 2 LASTPIN (2200 4550) $PN 110
J 0
(2210 4560);
DISPLAY 0.617021 (2210 4560);
PAINT ORANGE (2210 4560);
FORCEPROP 2 LASTPIN (2200 4500) $PN 111
J 0
(2210 4510);
DISPLAY 0.617021 (2210 4510);
PAINT ORANGE (2210 4510);
FORCEPROP 2 LASTPIN (2200 4450) $PN 99
J 0
(2210 4460);
DISPLAY 0.617021 (2210 4460);
PAINT ORANGE (2210 4460);
FORCEPROP 2 LASTPIN (2200 4400) $PN 100
J 0
(2210 4410);
DISPLAY 0.617021 (2210 4410);
PAINT ORANGE (2210 4410);
FORCEPROP 2 LASTPIN (2200 4350) $PN 40
J 0
(2210 4360);
DISPLAY 0.617021 (2210 4360);
PAINT ORANGE (2210 4360);
FORCEPROP 2 LASTPIN (2200 4300) $PN 41
J 0
(2210 4310);
DISPLAY 0.617021 (2210 4310);
PAINT ORANGE (2210 4310);
FORCEPROP 2 LASTPIN (2200 4250) $PN 29
J 0
(2210 4260);
DISPLAY 0.617021 (2210 4260);
PAINT ORANGE (2210 4260);
FORCEPROP 2 LASTPIN (2200 4200) $PN 30
J 0
(2210 4210);
DISPLAY 0.617021 (2210 4210);
PAINT ORANGE (2210 4210);
FORCEPROP 2 LASTPIN (2200 4150) $PN 18
J 0
(2210 4160);
DISPLAY 0.617021 (2210 4160);
PAINT ORANGE (2210 4160);
FORCEPROP 2 LASTPIN (2200 4100) $PN 19
J 0
(2210 4110);
DISPLAY 0.617021 (2210 4110);
PAINT ORANGE (2210 4110);
FORCEPROP 2 LASTPIN (2200 4050) $PN 7
J 0
(2210 4060);
DISPLAY 0.617021 (2210 4060);
PAINT ORANGE (2210 4060);
FORCEPROP 2 LASTPIN (2200 4000) $PN 8
J 0
(2210 4010);
DISPLAY 0.617021 (2210 4010);
PAINT ORANGE (2210 4010);
FORCEPROP 2 LASTPIN (2200 3950) $PN 197
J 0
(2210 3960);
DISPLAY 0.617021 (2210 3960);
PAINT ORANGE (2210 3960);
FORCEPROP 2 LASTPIN (2200 3900) $PN 196
J 0
(2210 3910);
DISPLAY 0.617021 (2210 3910);
PAINT ORANGE (2210 3910);
FORCEPROP 2 LASTPIN (2200 3850) $PN 278
J 0
(2210 3860);
DISPLAY 0.617021 (2210 3860);
PAINT ORANGE (2210 3860);
FORCEPROP 2 LASTPIN (2200 3800) $PN 277
J 0
(2210 3810);
DISPLAY 0.617021 (2210 3810);
PAINT ORANGE (2210 3810);
FORCEPROP 2 LASTPIN (2200 3750) $PN 267
J 0
(2210 3760);
DISPLAY 0.617021 (2210 3760);
PAINT ORANGE (2210 3760);
FORCEPROP 2 LASTPIN (2200 3700) $PN 266
J 0
(2210 3710);
DISPLAY 0.617021 (2210 3710);
PAINT ORANGE (2210 3710);
FORCEPROP 2 LASTPIN (2200 3650) $PN 256
J 0
(2210 3660);
DISPLAY 0.617021 (2210 3660);
PAINT ORANGE (2210 3660);
FORCEPROP 2 LASTPIN (2200 3600) $PN 255
J 0
(2210 3610);
DISPLAY 0.617021 (2210 3610);
PAINT ORANGE (2210 3610);
FORCEPROP 2 LASTPIN (2200 3550) $PN 245
J 0
(2210 3560);
DISPLAY 0.617021 (2210 3560);
PAINT ORANGE (2210 3560);
FORCEPROP 2 LASTPIN (2200 3500) $PN 244
J 0
(2210 3510);
DISPLAY 0.617021 (2210 3510);
PAINT ORANGE (2210 3510);
FORCEPROP 2 LASTPIN (2200 3450) $PN 186
J 0
(2210 3460);
DISPLAY 0.617021 (2210 3460);
PAINT ORANGE (2210 3460);
FORCEPROP 2 LASTPIN (2200 3400) $PN 185
J 0
(2210 3410);
DISPLAY 0.617021 (2210 3410);
PAINT ORANGE (2210 3410);
FORCEPROP 2 LASTPIN (2200 3350) $PN 175
J 0
(2210 3360);
DISPLAY 0.617021 (2210 3360);
PAINT ORANGE (2210 3360);
FORCEPROP 2 LASTPIN (2200 3300) $PN 174
J 0
(2210 3310);
DISPLAY 0.617021 (2210 3310);
PAINT ORANGE (2210 3310);
FORCEPROP 2 LASTPIN (2200 3250) $PN 164
J 0
(2210 3260);
DISPLAY 0.617021 (2210 3260);
PAINT ORANGE (2210 3260);
FORCEPROP 2 LASTPIN (2200 3200) $PN 163
J 0
(2210 3210);
DISPLAY 0.617021 (2210 3210);
PAINT ORANGE (2210 3210);
FORCEPROP 2 LASTPIN (2200 3150) $PN 153
J 0
(2210 3160);
DISPLAY 0.617021 (2210 3160);
PAINT ORANGE (2210 3160);
FORCEPROP 2 LASTPIN (2200 3100) $PN 152
J 0
(2210 3110);
DISPLAY 0.617021 (2210 3110);
PAINT ORANGE (2210 3110);
FORCEPROP 1 LAST PACK_TYPE PIP
J 0
(1350 5150);
PAINT SKYBLUE (1350 5150);
DISPLAY INVISIBLE (1350 5150);
FORCEPROP 2 LAST BOM_COST MEM
J 0
(1750 4000);
PAINT ORANGE (1750 4000);
DISPLAY INVISIBLE (1750 4000);
FORCEPROP 2 LAST CDS_LIB mstr_sconn
J 0
(1750 4000);
PAINT ORANGE (1750 4000);
DISPLAY INVISIBLE (1750 4000);
FORCEPROP 2 LAST SEC_TYPE PIP
J 0
(1350 5150);
DISPLAY 1.021277 (1350 5150);
PAINT ORANGE (1350 5150);
DISPLAY INVISIBLE (1350 5150);
FORCEPROP 2 LAST SEC 2
J 0
(1350 5150);
DISPLAY 0.680851 (1350 5150);
PAINT MONO (1350 5150);
DISPLAY INVISIBLE (1350 5150);
FORCEPROP 2 LAST CDS_LOCATION J9T1
J 0
(1350 5100);
DISPLAY 0.617021 (1350 5100);
PAINT AQUA (1350 5100);
DISPLAY INVISIBLE (1350 5100);
FORCEPROP 1 LAST PATH I120
J 0
(1750 5050);
PAINT GREEN (1750 5050);
DISPLAY INVISIBLE (1750 5050);
FORCEPROP 2 LAST ROOM DDR4_GH_G
J 0
(1750 4000);
PAINT ORANGE (1750 4000);
DISPLAY INVISIBLE (1750 4000);
FORCEADD OFFPAGE..1
(-2025 4275);
FORCEPROP 2 LAST $XR0 57 
J 0
(-2246 4275);
DISPLAY 0.638298 (-2246 4275);
PAINT MONO (-2246 4275);
FORCEPROP 2 LAST $XR1 77 
J 0
(-2336 4275);
DISPLAY 0.638298 (-2336 4275);
PAINT MONO (-2336 4275);
FORCEPROP 2 LAST CDS_LIB mstr_standard
J 0
(-2025 4275);
DISPLAY 0.787234 (-2025 4275);
PAINT MONO (-2025 4275);
DISPLAY INVISIBLE (-2025 4275);
FORCEPROP 1 LAST OFFPAGE TRUE
J 0
(-1700 4150);
DISPLAY 0.936170 (-1700 4150);
PAINT GREEN (-1700 4150);
DISPLAY INVISIBLE (-1700 4150);
FORCEPROP 1 LAST COMMENT_BODY TRUE
J 0
(-1900 4175);
DISPLAY 0.936170 (-1900 4175);
PAINT GREEN (-1900 4175);
DISPLAY INVISIBLE (-1900 4175);
FORCEPROP 2 LAST PATH I121
J 0
(-2225 4325);
DISPLAY 1.021277 (-2225 4325);
PAINT ORANGE (-2225 4325);
DISPLAY INVISIBLE (-2225 4325);
FORCEADD TAP..6
(-1375 3925);
FORCEPROP 3 LASTPIN (-1325 3925) SIG_NAME M_G_MA<11>
J 0
(-1315 3935);
DISPLAY 0.659574 (-1315 3935);
PAINT MONO (-1315 3935);
DISPLAY INVISIBLE (-1315 3935);
FORCEPROP 1 LASTPIN (-1325 3925) BN 11
J 0
(-1375 3935);
DISPLAY 0.617021 (-1375 3935);
PAINT PINK (-1375 3935);
FORCEPROP 2 LAST CDS_LIB mstr_standard
J 2
(-1375 3925);
DISPLAY 0.787234 (-1375 3925);
PAINT MONO (-1375 3925);
DISPLAY INVISIBLE (-1375 3925);
FORCEPROP 1 LAST BODY_TYPE PLUMBING
J 0
(-1375 3875);
DISPLAY 1.234043 (-1375 3875);
PAINT GREEN (-1375 3875);
DISPLAY INVISIBLE (-1375 3875);
FORCEPROP 1 LAST HDL_TAP TRUE
J 0
(-1050 3800);
DISPLAY 1.234043 (-1050 3800);
PAINT GREEN (-1050 3800);
DISPLAY INVISIBLE (-1050 3800);
FORCEPROP 1 LAST PATH I122
J 0
(-1377 3925);
DISPLAY 0.872340 (-1377 3925);
PAINT GREEN (-1377 3925);
DISPLAY INVISIBLE (-1377 3925);
FORCEADD TAP..6
(-1375 3975);
FORCEPROP 3 LASTPIN (-1325 3975) SIG_NAME M_G_MA<12>
J 0
(-1315 3985);
DISPLAY 0.659574 (-1315 3985);
PAINT MONO (-1315 3985);
DISPLAY INVISIBLE (-1315 3985);
FORCEPROP 1 LASTPIN (-1325 3975) BN 12
J 0
(-1375 3985);
DISPLAY 0.617021 (-1375 3985);
PAINT PINK (-1375 3985);
FORCEPROP 2 LAST CDS_LIB mstr_standard
J 2
(-1375 3975);
DISPLAY 0.787234 (-1375 3975);
PAINT MONO (-1375 3975);
DISPLAY INVISIBLE (-1375 3975);
FORCEPROP 1 LAST BODY_TYPE PLUMBING
J 0
(-1375 3925);
DISPLAY 1.234043 (-1375 3925);
PAINT GREEN (-1375 3925);
DISPLAY INVISIBLE (-1375 3925);
FORCEPROP 1 LAST HDL_TAP TRUE
J 0
(-1050 3850);
DISPLAY 1.234043 (-1050 3850);
PAINT GREEN (-1050 3850);
DISPLAY INVISIBLE (-1050 3850);
FORCEPROP 1 LAST PATH I123
J 0
(-1377 3975);
DISPLAY 0.872340 (-1377 3975);
PAINT GREEN (-1377 3975);
DISPLAY INVISIBLE (-1377 3975);
FORCEADD TAP..6
(-1375 4125);
FORCEPROP 3 LASTPIN (-1325 4125) SIG_NAME M_G_MA<15>
J 0
(-1315 4135);
DISPLAY 0.659574 (-1315 4135);
PAINT MONO (-1315 4135);
DISPLAY INVISIBLE (-1315 4135);
FORCEPROP 1 LASTPIN (-1325 4125) BN 15
J 0
(-1375 4135);
DISPLAY 0.617021 (-1375 4135);
PAINT PINK (-1375 4135);
FORCEPROP 2 LAST CDS_LIB mstr_standard
J 2
(-1375 4125);
DISPLAY 0.787234 (-1375 4125);
PAINT MONO (-1375 4125);
DISPLAY INVISIBLE (-1375 4125);
FORCEPROP 1 LAST BODY_TYPE PLUMBING
J 0
(-1375 4075);
DISPLAY 1.234043 (-1375 4075);
PAINT GREEN (-1375 4075);
DISPLAY INVISIBLE (-1375 4075);
FORCEPROP 1 LAST HDL_TAP TRUE
J 0
(-1050 4000);
DISPLAY 1.234043 (-1050 4000);
PAINT GREEN (-1050 4000);
DISPLAY INVISIBLE (-1050 4000);
FORCEPROP 1 LAST PATH I124
J 0
(-1377 4125);
DISPLAY 0.872340 (-1377 4125);
PAINT GREEN (-1377 4125);
DISPLAY INVISIBLE (-1377 4125);
FORCEADD TAP..6
(-1375 4075);
FORCEPROP 3 LASTPIN (-1325 4075) SIG_NAME M_G_MA<14>
J 0
(-1315 4085);
DISPLAY 0.659574 (-1315 4085);
PAINT MONO (-1315 4085);
DISPLAY INVISIBLE (-1315 4085);
FORCEPROP 1 LASTPIN (-1325 4075) BN 14
J 0
(-1375 4085);
DISPLAY 0.617021 (-1375 4085);
PAINT PINK (-1375 4085);
FORCEPROP 2 LAST CDS_LIB mstr_standard
J 2
(-1375 4075);
DISPLAY 0.787234 (-1375 4075);
PAINT MONO (-1375 4075);
DISPLAY INVISIBLE (-1375 4075);
FORCEPROP 1 LAST BODY_TYPE PLUMBING
J 0
(-1375 4025);
DISPLAY 1.234043 (-1375 4025);
PAINT GREEN (-1375 4025);
DISPLAY INVISIBLE (-1375 4025);
FORCEPROP 1 LAST HDL_TAP TRUE
J 0
(-1050 3950);
DISPLAY 1.234043 (-1050 3950);
PAINT GREEN (-1050 3950);
DISPLAY INVISIBLE (-1050 3950);
FORCEPROP 1 LAST PATH I125
J 0
(-1377 4075);
DISPLAY 0.872340 (-1377 4075);
PAINT GREEN (-1377 4075);
DISPLAY INVISIBLE (-1377 4075);
FORCEADD TAP..6
(-1375 4025);
FORCEPROP 3 LASTPIN (-1325 4025) SIG_NAME M_G_MA<13>
J 0
(-1315 4035);
DISPLAY 0.659574 (-1315 4035);
PAINT MONO (-1315 4035);
DISPLAY INVISIBLE (-1315 4035);
FORCEPROP 1 LASTPIN (-1325 4025) BN 13
J 0
(-1375 4035);
DISPLAY 0.617021 (-1375 4035);
PAINT PINK (-1375 4035);
FORCEPROP 2 LAST CDS_LIB mstr_standard
J 2
(-1375 4025);
DISPLAY 0.787234 (-1375 4025);
PAINT MONO (-1375 4025);
DISPLAY INVISIBLE (-1375 4025);
FORCEPROP 1 LAST BODY_TYPE PLUMBING
J 0
(-1375 3975);
DISPLAY 1.234043 (-1375 3975);
PAINT GREEN (-1375 3975);
DISPLAY INVISIBLE (-1375 3975);
FORCEPROP 1 LAST HDL_TAP TRUE
J 0
(-1050 3900);
DISPLAY 1.234043 (-1050 3900);
PAINT GREEN (-1050 3900);
DISPLAY INVISIBLE (-1050 3900);
FORCEPROP 1 LAST PATH I126
J 0
(-1377 4025);
DISPLAY 0.872340 (-1377 4025);
PAINT GREEN (-1377 4025);
DISPLAY INVISIBLE (-1377 4025);
FORCEADD TAP..6
(-1375 4225);
FORCEPROP 3 LASTPIN (-1325 4225) SIG_NAME M_G_MA<17>
J 0
(-1315 4235);
DISPLAY 0.659574 (-1315 4235);
PAINT MONO (-1315 4235);
DISPLAY INVISIBLE (-1315 4235);
FORCEPROP 1 LASTPIN (-1325 4225) BN 17
J 0
(-1375 4235);
DISPLAY 0.617021 (-1375 4235);
PAINT PINK (-1375 4235);
FORCEPROP 2 LAST CDS_LIB mstr_standard
J 0
(-1375 4225);
DISPLAY 0.787234 (-1375 4225);
PAINT MONO (-1375 4225);
DISPLAY INVISIBLE (-1375 4225);
FORCEPROP 1 LAST BODY_TYPE PLUMBING
J 0
(-1375 4175);
DISPLAY 1.234043 (-1375 4175);
PAINT GREEN (-1375 4175);
DISPLAY INVISIBLE (-1375 4175);
FORCEPROP 1 LAST HDL_TAP TRUE
J 0
(-1050 4100);
DISPLAY 1.234043 (-1050 4100);
PAINT GREEN (-1050 4100);
DISPLAY INVISIBLE (-1050 4100);
FORCEPROP 1 LAST PATH I127
J 0
(-1377 4225);
DISPLAY 0.872340 (-1377 4225);
PAINT GREEN (-1377 4225);
DISPLAY INVISIBLE (-1377 4225);
FORCEADD TAP..6
(-1375 4175);
FORCEPROP 3 LASTPIN (-1325 4175) SIG_NAME M_G_MA<16>
J 0
(-1315 4185);
DISPLAY 0.659574 (-1315 4185);
PAINT MONO (-1315 4185);
DISPLAY INVISIBLE (-1315 4185);
FORCEPROP 1 LASTPIN (-1325 4175) BN 16
J 0
(-1375 4185);
DISPLAY 0.617021 (-1375 4185);
PAINT PINK (-1375 4185);
FORCEPROP 2 LAST CDS_LIB mstr_standard
J 2
(-1375 4175);
DISPLAY 0.787234 (-1375 4175);
PAINT MONO (-1375 4175);
DISPLAY INVISIBLE (-1375 4175);
FORCEPROP 1 LAST BODY_TYPE PLUMBING
J 0
(-1375 4125);
DISPLAY 1.234043 (-1375 4125);
PAINT GREEN (-1375 4125);
DISPLAY INVISIBLE (-1375 4125);
FORCEPROP 1 LAST HDL_TAP TRUE
J 0
(-1050 4050);
DISPLAY 1.234043 (-1050 4050);
PAINT GREEN (-1050 4050);
DISPLAY INVISIBLE (-1050 4050);
FORCEPROP 1 LAST PATH I128
J 0
(-1377 4175);
DISPLAY 0.872340 (-1377 4175);
PAINT GREEN (-1377 4175);
DISPLAY INVISIBLE (-1377 4175);
FORCEADD SCONN288_H44441003..1
(-625 2575);
FORCEPROP 1 LAST LOCATION J9T1
J 0
(-1075 4475);
DISPLAY 0.617021 (-1075 4475);
PAINT AQUA (-1075 4475);
FORCEPROP 1 LAST PART_NUMBER H44441-003
J 0
(-1075 575);
DISPLAY 0.617021 (-1075 575);
PAINT BLUE (-1075 575);
FORCEPROP 1 LAST MATERIAL SCONN
J 0
(-1075 4425);
DISPLAY 0.617021 (-1075 4425);
PAINT SKYBLUE (-1075 4425);
FORCEPROP 2 LASTPIN (-1125 1075) $PN 146
J 2
(-1135 1085);
DISPLAY 0.617021 (-1135 1085);
PAINT ORANGE (-1135 1085);
FORCEPROP 2 LASTPIN (-1125 1425) $PN 284
J 2
(-1135 1435);
DISPLAY 0.617021 (-1135 1435);
PAINT ORANGE (-1135 1435);
FORCEPROP 2 LASTPIN (-1125 1225) $PN 285
J 2
(-1135 1235);
DISPLAY 0.617021 (-1135 1235);
PAINT ORANGE (-1135 1235);
FORCEPROP 2 LASTPIN (-1125 1175) $PN 141
J 2
(-1135 1185);
DISPLAY 0.617021 (-1135 1185);
PAINT ORANGE (-1135 1185);
FORCEPROP 2 LASTPIN (-1125 775) $PN 230
J 2
(-1135 785);
DISPLAY 0.617021 (-1135 785);
PAINT ORANGE (-1135 785);
FORCEPROP 2 LASTPIN (-1125 1375) $PN 238
J 2
(-1135 1385);
DISPLAY 0.617021 (-1135 1385);
PAINT ORANGE (-1135 1385);
FORCEPROP 2 LASTPIN (-1125 1325) $PN 140
J 2
(-1135 1335);
DISPLAY 0.617021 (-1135 1335);
PAINT ORANGE (-1135 1335);
FORCEPROP 2 LASTPIN (-1125 1275) $PN 139
J 2
(-1135 1285);
DISPLAY 0.617021 (-1135 1285);
PAINT ORANGE (-1135 1285);
FORCEPROP 2 LASTPIN (-1125 2725) $PN 237
J 2
(-1135 2735);
DISPLAY 0.617021 (-1135 2735);
PAINT ORANGE (-1135 2735);
FORCEPROP 2 LASTPIN (-1125 2675) $PN 93
J 2
(-1135 2685);
DISPLAY 0.617021 (-1135 2685);
PAINT ORANGE (-1135 2685);
FORCEPROP 2 LASTPIN (-1125 2625) $PN 89
J 2
(-1135 2635);
DISPLAY 0.617021 (-1135 2635);
PAINT ORANGE (-1135 2635);
FORCEPROP 2 LASTPIN (-1125 2575) $PN 84
J 2
(-1135 2585);
DISPLAY 0.617021 (-1135 2585);
PAINT ORANGE (-1135 2585);
FORCEPROP 2 LASTPIN (-1125 975) $PN 144
J 2
(-1135 985);
DISPLAY 0.617021 (-1135 985);
PAINT ORANGE (-1135 985);
FORCEPROP 2 LASTPIN (-1125 925) $PN 227
J 2
(-1135 935);
DISPLAY 0.617021 (-1135 935);
PAINT ORANGE (-1135 935);
FORCEPROP 2 LASTPIN (-1125 875) $PN 205
J 2
(-1135 885);
DISPLAY 0.617021 (-1135 885);
PAINT ORANGE (-1135 885);
FORCEPROP 2 LASTPIN (-1125 1675) $PN 58
J 2
(-1135 1685);
DISPLAY 0.617021 (-1135 1685);
PAINT ORANGE (-1135 1685);
FORCEPROP 2 LASTPIN (-1125 1725) $PN 222
J 2
(-1135 1735);
DISPLAY 0.617021 (-1135 1735);
PAINT ORANGE (-1135 1735);
FORCEPROP 2 LASTPIN (-1125 2325) $PN 91
J 2
(-1135 2335);
DISPLAY 0.617021 (-1135 2335);
PAINT ORANGE (-1135 2335);
FORCEPROP 2 LASTPIN (-1125 2275) $PN 87
J 2
(-1135 2285);
DISPLAY 0.617021 (-1135 2285);
PAINT ORANGE (-1135 2285);
FORCEPROP 2 LASTPIN (-1125 1625) $PN 78
J 2
(-1135 1635);
DISPLAY 0.617021 (-1135 1635);
PAINT ORANGE (-1135 1635);
FORCEPROP 2 LASTPIN (-125 4225) $PN 280
J 0
(-115 4235);
DISPLAY 0.617021 (-115 4235);
PAINT ORANGE (-115 4235);
FORCEPROP 2 LASTPIN (-125 4175) $PN 135
J 0
(-115 4185);
DISPLAY 0.617021 (-115 4185);
PAINT ORANGE (-115 4185);
FORCEPROP 2 LASTPIN (-125 4125) $PN 273
J 0
(-115 4135);
DISPLAY 0.617021 (-115 4135);
PAINT ORANGE (-115 4135);
FORCEPROP 2 LASTPIN (-125 4075) $PN 128
J 0
(-115 4085);
DISPLAY 0.617021 (-115 4085);
PAINT ORANGE (-115 4085);
FORCEPROP 2 LASTPIN (-125 4025) $PN 282
J 0
(-115 4035);
DISPLAY 0.617021 (-115 4035);
PAINT ORANGE (-115 4035);
FORCEPROP 2 LASTPIN (-125 3975) $PN 137
J 0
(-115 3985);
DISPLAY 0.617021 (-115 3985);
PAINT ORANGE (-115 3985);
FORCEPROP 2 LASTPIN (-125 3925) $PN 275
J 0
(-115 3935);
DISPLAY 0.617021 (-115 3935);
PAINT ORANGE (-115 3935);
FORCEPROP 2 LASTPIN (-125 3875) $PN 130
J 0
(-115 3885);
DISPLAY 0.617021 (-115 3885);
PAINT ORANGE (-115 3885);
FORCEPROP 2 LASTPIN (-125 3825) $PN 269
J 0
(-115 3835);
DISPLAY 0.617021 (-115 3835);
PAINT ORANGE (-115 3835);
FORCEPROP 2 LASTPIN (-125 3775) $PN 124
J 0
(-115 3785);
DISPLAY 0.617021 (-115 3785);
PAINT ORANGE (-115 3785);
FORCEPROP 2 LASTPIN (-125 3725) $PN 262
J 0
(-115 3735);
DISPLAY 0.617021 (-115 3735);
PAINT ORANGE (-115 3735);
FORCEPROP 2 LASTPIN (-125 3675) $PN 117
J 0
(-115 3685);
DISPLAY 0.617021 (-115 3685);
PAINT ORANGE (-115 3685);
FORCEPROP 2 LASTPIN (-125 3625) $PN 271
J 0
(-115 3635);
DISPLAY 0.617021 (-115 3635);
PAINT ORANGE (-115 3635);
FORCEPROP 2 LASTPIN (-125 3575) $PN 126
J 0
(-115 3585);
DISPLAY 0.617021 (-115 3585);
PAINT ORANGE (-115 3585);
FORCEPROP 2 LASTPIN (-125 3525) $PN 264
J 0
(-115 3535);
DISPLAY 0.617021 (-115 3535);
PAINT ORANGE (-115 3535);
FORCEPROP 2 LASTPIN (-125 3475) $PN 119
J 0
(-115 3485);
DISPLAY 0.617021 (-115 3485);
PAINT ORANGE (-115 3485);
FORCEPROP 2 LASTPIN (-125 3425) $PN 258
J 0
(-115 3435);
DISPLAY 0.617021 (-115 3435);
PAINT ORANGE (-115 3435);
FORCEPROP 2 LASTPIN (-125 3375) $PN 113
J 0
(-115 3385);
DISPLAY 0.617021 (-115 3385);
PAINT ORANGE (-115 3385);
FORCEPROP 2 LASTPIN (-125 3325) $PN 251
J 0
(-115 3335);
DISPLAY 0.617021 (-115 3335);
PAINT ORANGE (-115 3335);
FORCEPROP 2 LASTPIN (-125 3275) $PN 106
J 0
(-115 3285);
DISPLAY 0.617021 (-115 3285);
PAINT ORANGE (-115 3285);
FORCEPROP 2 LASTPIN (-125 3225) $PN 260
J 0
(-115 3235);
DISPLAY 0.617021 (-115 3235);
PAINT ORANGE (-115 3235);
FORCEPROP 2 LASTPIN (-125 3175) $PN 115
J 0
(-115 3185);
DISPLAY 0.617021 (-115 3185);
PAINT ORANGE (-115 3185);
FORCEPROP 2 LASTPIN (-125 3125) $PN 253
J 0
(-115 3135);
DISPLAY 0.617021 (-115 3135);
PAINT ORANGE (-115 3135);
FORCEPROP 2 LASTPIN (-125 3075) $PN 108
J 0
(-115 3085);
DISPLAY 0.617021 (-115 3085);
PAINT ORANGE (-115 3085);
FORCEPROP 2 LASTPIN (-125 3025) $PN 247
J 0
(-115 3035);
DISPLAY 0.617021 (-115 3035);
PAINT ORANGE (-115 3035);
FORCEPROP 2 LASTPIN (-125 2975) $PN 102
J 0
(-115 2985);
DISPLAY 0.617021 (-115 2985);
PAINT ORANGE (-115 2985);
FORCEPROP 2 LASTPIN (-125 2925) $PN 240
J 0
(-115 2935);
DISPLAY 0.617021 (-115 2935);
PAINT ORANGE (-115 2935);
FORCEPROP 2 LASTPIN (-125 2875) $PN 95
J 0
(-115 2885);
DISPLAY 0.617021 (-115 2885);
PAINT ORANGE (-115 2885);
FORCEPROP 2 LASTPIN (-125 2825) $PN 249
J 0
(-115 2835);
DISPLAY 0.617021 (-115 2835);
PAINT ORANGE (-115 2835);
FORCEPROP 2 LASTPIN (-125 2775) $PN 104
J 0
(-115 2785);
DISPLAY 0.617021 (-115 2785);
PAINT ORANGE (-115 2785);
FORCEPROP 2 LASTPIN (-125 2725) $PN 242
J 0
(-115 2735);
DISPLAY 0.617021 (-115 2735);
PAINT ORANGE (-115 2735);
FORCEPROP 2 LASTPIN (-125 2675) $PN 97
J 0
(-115 2685);
DISPLAY 0.617021 (-115 2685);
PAINT ORANGE (-115 2685);
FORCEPROP 2 LASTPIN (-125 2625) $PN 188
J 0
(-115 2635);
DISPLAY 0.617021 (-115 2635);
PAINT ORANGE (-115 2635);
FORCEPROP 2 LASTPIN (-125 2575) $PN 43
J 0
(-115 2585);
DISPLAY 0.617021 (-115 2585);
PAINT ORANGE (-115 2585);
FORCEPROP 2 LASTPIN (-125 2525) $PN 181
J 0
(-115 2535);
DISPLAY 0.617021 (-115 2535);
PAINT ORANGE (-115 2535);
FORCEPROP 2 LASTPIN (-125 2475) $PN 36
J 0
(-115 2485);
DISPLAY 0.617021 (-115 2485);
PAINT ORANGE (-115 2485);
FORCEPROP 2 LASTPIN (-125 2425) $PN 190
J 0
(-115 2435);
DISPLAY 0.617021 (-115 2435);
PAINT ORANGE (-115 2435);
FORCEPROP 2 LASTPIN (-125 2375) $PN 45
J 0
(-115 2385);
DISPLAY 0.617021 (-115 2385);
PAINT ORANGE (-115 2385);
FORCEPROP 2 LASTPIN (-125 2325) $PN 183
J 0
(-115 2335);
DISPLAY 0.617021 (-115 2335);
PAINT ORANGE (-115 2335);
FORCEPROP 2 LASTPIN (-125 2275) $PN 38
J 0
(-115 2285);
DISPLAY 0.617021 (-115 2285);
PAINT ORANGE (-115 2285);
FORCEPROP 2 LASTPIN (-125 2225) $PN 177
J 0
(-115 2235);
DISPLAY 0.617021 (-115 2235);
PAINT ORANGE (-115 2235);
FORCEPROP 2 LASTPIN (-125 2175) $PN 32
J 0
(-115 2185);
DISPLAY 0.617021 (-115 2185);
PAINT ORANGE (-115 2185);
FORCEPROP 2 LASTPIN (-125 2125) $PN 170
J 0
(-115 2135);
DISPLAY 0.617021 (-115 2135);
PAINT ORANGE (-115 2135);
FORCEPROP 2 LASTPIN (-125 2075) $PN 25
J 0
(-115 2085);
DISPLAY 0.617021 (-115 2085);
PAINT ORANGE (-115 2085);
FORCEPROP 2 LASTPIN (-125 2025) $PN 179
J 0
(-115 2035);
DISPLAY 0.617021 (-115 2035);
PAINT ORANGE (-115 2035);
FORCEPROP 2 LASTPIN (-125 1975) $PN 34
J 0
(-115 1985);
DISPLAY 0.617021 (-115 1985);
PAINT ORANGE (-115 1985);
FORCEPROP 2 LASTPIN (-125 1925) $PN 172
J 0
(-115 1935);
DISPLAY 0.617021 (-115 1935);
PAINT ORANGE (-115 1935);
FORCEPROP 2 LASTPIN (-125 1875) $PN 27
J 0
(-115 1885);
DISPLAY 0.617021 (-115 1885);
PAINT ORANGE (-115 1885);
FORCEPROP 2 LASTPIN (-125 1825) $PN 166
J 0
(-115 1835);
DISPLAY 0.617021 (-115 1835);
PAINT ORANGE (-115 1835);
FORCEPROP 2 LASTPIN (-125 1775) $PN 21
J 0
(-115 1785);
DISPLAY 0.617021 (-115 1785);
PAINT ORANGE (-115 1785);
FORCEPROP 2 LASTPIN (-125 1725) $PN 159
J 0
(-115 1735);
DISPLAY 0.617021 (-115 1735);
PAINT ORANGE (-115 1735);
FORCEPROP 2 LASTPIN (-125 1675) $PN 14
J 0
(-115 1685);
DISPLAY 0.617021 (-115 1685);
PAINT ORANGE (-115 1685);
FORCEPROP 2 LASTPIN (-125 1625) $PN 168
J 0
(-115 1635);
DISPLAY 0.617021 (-115 1635);
PAINT ORANGE (-115 1635);
FORCEPROP 2 LASTPIN (-125 1575) $PN 23
J 0
(-115 1585);
DISPLAY 0.617021 (-115 1585);
PAINT ORANGE (-115 1585);
FORCEPROP 2 LASTPIN (-125 1525) $PN 161
J 0
(-115 1535);
DISPLAY 0.617021 (-115 1535);
PAINT ORANGE (-115 1535);
FORCEPROP 2 LASTPIN (-125 1475) $PN 16
J 0
(-115 1485);
DISPLAY 0.617021 (-115 1485);
PAINT ORANGE (-115 1485);
FORCEPROP 2 LASTPIN (-125 1425) $PN 155
J 0
(-115 1435);
DISPLAY 0.617021 (-115 1435);
PAINT ORANGE (-115 1435);
FORCEPROP 2 LASTPIN (-125 1375) $PN 10
J 0
(-115 1385);
DISPLAY 0.617021 (-115 1385);
PAINT ORANGE (-115 1385);
FORCEPROP 2 LASTPIN (-125 1325) $PN 148
J 0
(-115 1335);
DISPLAY 0.617021 (-115 1335);
PAINT ORANGE (-115 1335);
FORCEPROP 2 LASTPIN (-125 1275) $PN 3
J 0
(-115 1285);
DISPLAY 0.617021 (-115 1285);
PAINT ORANGE (-115 1285);
FORCEPROP 2 LASTPIN (-125 1225) $PN 157
J 0
(-115 1235);
DISPLAY 0.617021 (-115 1235);
PAINT ORANGE (-115 1235);
FORCEPROP 2 LASTPIN (-125 1175) $PN 12
J 0
(-115 1185);
DISPLAY 0.617021 (-115 1185);
PAINT ORANGE (-115 1185);
FORCEPROP 2 LASTPIN (-125 1125) $PN 150
J 0
(-115 1135);
DISPLAY 0.617021 (-115 1135);
PAINT ORANGE (-115 1135);
FORCEPROP 2 LASTPIN (-125 1075) $PN 5
J 0
(-115 1085);
DISPLAY 0.617021 (-115 1085);
PAINT ORANGE (-115 1085);
FORCEPROP 2 LASTPIN (-1125 2475) $PN 203
J 2
(-1135 2485);
DISPLAY 0.617021 (-1135 2485);
PAINT ORANGE (-1135 2485);
FORCEPROP 2 LASTPIN (-1125 2425) $PN 60
J 2
(-1135 2435);
DISPLAY 0.617021 (-1135 2435);
PAINT ORANGE (-1135 2435);
FORCEPROP 2 LASTPIN (-1125 3025) $PN 218
J 2
(-1135 3035);
DISPLAY 0.617021 (-1135 3035);
PAINT ORANGE (-1135 3035);
FORCEPROP 2 LASTPIN (-1125 2975) $PN 219
J 2
(-1135 2985);
DISPLAY 0.617021 (-1135 2985);
PAINT ORANGE (-1135 2985);
FORCEPROP 2 LASTPIN (-1125 2925) $PN 74
J 2
(-1135 2935);
DISPLAY 0.617021 (-1135 2935);
PAINT ORANGE (-1135 2935);
FORCEPROP 2 LASTPIN (-1125 2875) $PN 75
J 2
(-1135 2885);
DISPLAY 0.617021 (-1135 2885);
PAINT ORANGE (-1135 2885);
FORCEPROP 2 LASTPIN (-1125 2175) $PN 199
J 2
(-1135 2185);
DISPLAY 0.617021 (-1135 2185);
PAINT ORANGE (-1135 2185);
FORCEPROP 2 LASTPIN (-1125 2125) $PN 54
J 2
(-1135 2135);
DISPLAY 0.617021 (-1135 2135);
PAINT ORANGE (-1135 2135);
FORCEPROP 2 LASTPIN (-1125 2075) $PN 192
J 2
(-1135 2085);
DISPLAY 0.617021 (-1135 2085);
PAINT ORANGE (-1135 2085);
FORCEPROP 2 LASTPIN (-1125 2025) $PN 47
J 2
(-1135 2035);
DISPLAY 0.617021 (-1135 2035);
PAINT ORANGE (-1135 2035);
FORCEPROP 2 LASTPIN (-1125 1975) $PN 201
J 2
(-1135 1985);
DISPLAY 0.617021 (-1135 1985);
PAINT ORANGE (-1135 1985);
FORCEPROP 2 LASTPIN (-1125 1925) $PN 56
J 2
(-1135 1935);
DISPLAY 0.617021 (-1135 1935);
PAINT ORANGE (-1135 1935);
FORCEPROP 2 LASTPIN (-1125 1875) $PN 194
J 2
(-1135 1885);
DISPLAY 0.617021 (-1135 1885);
PAINT ORANGE (-1135 1885);
FORCEPROP 2 LASTPIN (-1125 1825) $PN 49
J 2
(-1135 1835);
DISPLAY 0.617021 (-1135 1835);
PAINT ORANGE (-1135 1835);
FORCEPROP 2 LASTPIN (-1125 2775) $PN 235
J 2
(-1135 2785);
DISPLAY 0.617021 (-1135 2785);
PAINT ORANGE (-1135 2785);
FORCEPROP 2 LASTPIN (-1125 3175) $PN 207
J 2
(-1135 3185);
DISPLAY 0.617021 (-1135 3185);
PAINT ORANGE (-1135 3185);
FORCEPROP 2 LASTPIN (-1125 3125) $PN 63
J 2
(-1135 3135);
DISPLAY 0.617021 (-1135 3135);
PAINT ORANGE (-1135 3135);
FORCEPROP 2 LASTPIN (-1125 3275) $PN 224
J 2
(-1135 3285);
DISPLAY 0.617021 (-1135 3285);
PAINT ORANGE (-1135 3285);
FORCEPROP 2 LASTPIN (-1125 3225) $PN 81
J 2
(-1135 3235);
DISPLAY 0.617021 (-1135 3235);
PAINT ORANGE (-1135 3235);
FORCEPROP 2 LASTPIN (-1125 1575) $PN 208
J 2
(-1135 1585);
DISPLAY 0.617021 (-1135 1585);
PAINT ORANGE (-1135 1585);
FORCEPROP 2 LASTPIN (-1125 1525) $PN 62
J 2
(-1135 1535);
DISPLAY 0.617021 (-1135 1535);
PAINT ORANGE (-1135 1535);
FORCEPROP 2 LASTPIN (-1125 4225) $PN 234
J 2
(-1135 4235);
DISPLAY 0.617021 (-1135 4235);
PAINT ORANGE (-1135 4235);
FORCEPROP 2 LASTPIN (-1125 4175) $PN 82
J 2
(-1135 4185);
DISPLAY 0.617021 (-1135 4185);
PAINT ORANGE (-1135 4185);
FORCEPROP 2 LASTPIN (-1125 4125) $PN 86
J 2
(-1135 4135);
DISPLAY 0.617021 (-1135 4135);
PAINT ORANGE (-1135 4135);
FORCEPROP 2 LASTPIN (-1125 4075) $PN 228
J 2
(-1135 4085);
DISPLAY 0.617021 (-1135 4085);
PAINT ORANGE (-1135 4085);
FORCEPROP 2 LASTPIN (-1125 4025) $PN 232
J 2
(-1135 4035);
DISPLAY 0.617021 (-1135 4035);
PAINT ORANGE (-1135 4035);
FORCEPROP 2 LASTPIN (-1125 3975) $PN 65
J 2
(-1135 3985);
DISPLAY 0.617021 (-1135 3985);
PAINT ORANGE (-1135 3985);
FORCEPROP 2 LASTPIN (-1125 3925) $PN 210
J 2
(-1135 3935);
DISPLAY 0.617021 (-1135 3935);
PAINT ORANGE (-1135 3935);
FORCEPROP 2 LASTPIN (-1125 3875) $PN 225
J 2
(-1135 3885);
DISPLAY 0.617021 (-1135 3885);
PAINT ORANGE (-1135 3885);
FORCEPROP 2 LASTPIN (-1125 3825) $PN 66
J 2
(-1135 3835);
DISPLAY 0.617021 (-1135 3835);
PAINT ORANGE (-1135 3835);
FORCEPROP 2 LASTPIN (-1125 3775) $PN 68
J 2
(-1135 3785);
DISPLAY 0.617021 (-1135 3785);
PAINT ORANGE (-1135 3785);
FORCEPROP 2 LASTPIN (-1125 3725) $PN 211
J 2
(-1135 3735);
DISPLAY 0.617021 (-1135 3735);
PAINT ORANGE (-1135 3735);
FORCEPROP 2 LASTPIN (-1125 3675) $PN 69
J 2
(-1135 3685);
DISPLAY 0.617021 (-1135 3685);
PAINT ORANGE (-1135 3685);
FORCEPROP 2 LASTPIN (-1125 3625) $PN 213
J 2
(-1135 3635);
DISPLAY 0.617021 (-1135 3635);
PAINT ORANGE (-1135 3635);
FORCEPROP 2 LASTPIN (-1125 3575) $PN 214
J 2
(-1135 3585);
DISPLAY 0.617021 (-1135 3585);
PAINT ORANGE (-1135 3585);
FORCEPROP 2 LASTPIN (-1125 3525) $PN 71
J 2
(-1135 3535);
DISPLAY 0.617021 (-1135 3535);
PAINT ORANGE (-1135 3535);
FORCEPROP 2 LASTPIN (-1125 3475) $PN 216
J 2
(-1135 3485);
DISPLAY 0.617021 (-1135 3485);
PAINT ORANGE (-1135 3485);
FORCEPROP 2 LASTPIN (-1125 3425) $PN 72
J 2
(-1135 3435);
DISPLAY 0.617021 (-1135 3435);
PAINT ORANGE (-1135 3435);
FORCEPROP 2 LASTPIN (-1125 3375) $PN 79
J 2
(-1135 3385);
DISPLAY 0.617021 (-1135 3385);
PAINT ORANGE (-1135 3385);
FORCEPROP 1 LAST PACK_TYPE PIP
J 0
(-1075 4525);
PAINT SKYBLUE (-1075 4525);
DISPLAY INVISIBLE (-1075 4525);
FORCEPROP 2 LAST BOM_COST MEM
J 0
(-625 2575);
PAINT ORANGE (-625 2575);
DISPLAY INVISIBLE (-625 2575);
FORCEPROP 2 LAST CDS_LIB mstr_sconn
J 0
(-625 2575);
PAINT ORANGE (-625 2575);
DISPLAY INVISIBLE (-625 2575);
FORCEPROP 2 LAST SEC_TYPE PIP
J 0
(-1075 4525);
DISPLAY 1.021277 (-1075 4525);
PAINT ORANGE (-1075 4525);
DISPLAY INVISIBLE (-1075 4525);
FORCEPROP 2 LAST SEC 1
J 0
(-1075 4525);
DISPLAY 0.680851 (-1075 4525);
PAINT MONO (-1075 4525);
DISPLAY INVISIBLE (-1075 4525);
FORCEPROP 2 LAST CDS_LOCATION J9T1
J 0
(-1075 4475);
DISPLAY 0.617021 (-1075 4475);
PAINT AQUA (-1075 4475);
DISPLAY INVISIBLE (-1075 4475);
FORCEPROP 1 LAST PATH I13
J 0
(-625 4425);
PAINT GREEN (-625 4425);
DISPLAY INVISIBLE (-625 4425);
FORCEPROP 2 LAST ROOM DDR4_GH_G
J 0
(-625 2575);
PAINT ORANGE (-625 2575);
DISPLAY INVISIBLE (-625 2575);
FORCEADD TAP..6
R 2
(125 3975);
FORCEPROP 3 LASTPIN (75 3975) SIG_NAME M_G_DQ<58>
J 0
(85 3985);
DISPLAY 0.659574 (85 3985);
PAINT MONO (85 3985);
DISPLAY INVISIBLE (85 3985);
FORCEPROP 1 LASTPIN (75 3975) BN 58
J 2
(125 3985);
DISPLAY 0.617021 (125 3985);
PAINT PINK (125 3985);
FORCEPROP 2 LAST CDS_LIB mstr_standard
J 2
(125 3975);
DISPLAY 0.787234 (125 3975);
PAINT MONO (125 3975);
DISPLAY INVISIBLE (125 3975);
FORCEPROP 1 LAST BODY_TYPE PLUMBING
J 2
(125 3925);
DISPLAY 1.234043 (125 3925);
PAINT GREEN (125 3925);
DISPLAY INVISIBLE (125 3925);
FORCEPROP 1 LAST HDL_TAP TRUE
J 2
(-200 3850);
DISPLAY 1.234043 (-200 3850);
PAINT GREEN (-200 3850);
DISPLAY INVISIBLE (-200 3850);
FORCEPROP 1 LAST PATH I135
J 2
(127 3975);
DISPLAY 0.872340 (127 3975);
PAINT GREEN (127 3975);
DISPLAY INVISIBLE (127 3975);
FORCEADD TAP..6
R 2
(125 3925);
FORCEPROP 3 LASTPIN (75 3925) SIG_NAME M_G_DQ<57>
J 0
(85 3935);
DISPLAY 0.659574 (85 3935);
PAINT MONO (85 3935);
DISPLAY INVISIBLE (85 3935);
FORCEPROP 1 LASTPIN (75 3925) BN 57
J 2
(125 3935);
DISPLAY 0.617021 (125 3935);
PAINT PINK (125 3935);
FORCEPROP 2 LAST CDS_LIB mstr_standard
J 2
(125 3925);
DISPLAY 0.787234 (125 3925);
PAINT MONO (125 3925);
DISPLAY INVISIBLE (125 3925);
FORCEPROP 1 LAST BODY_TYPE PLUMBING
J 2
(125 3875);
DISPLAY 1.234043 (125 3875);
PAINT GREEN (125 3875);
DISPLAY INVISIBLE (125 3875);
FORCEPROP 1 LAST HDL_TAP TRUE
J 2
(-200 3800);
DISPLAY 1.234043 (-200 3800);
PAINT GREEN (-200 3800);
DISPLAY INVISIBLE (-200 3800);
FORCEPROP 1 LAST PATH I136
J 2
(127 3925);
DISPLAY 0.872340 (127 3925);
PAINT GREEN (127 3925);
DISPLAY INVISIBLE (127 3925);
FORCEADD TAP..6
R 2
(125 4025);
FORCEPROP 3 LASTPIN (75 4025) SIG_NAME M_G_DQ<59>
J 0
(85 4035);
DISPLAY 0.659574 (85 4035);
PAINT MONO (85 4035);
DISPLAY INVISIBLE (85 4035);
FORCEPROP 1 LASTPIN (75 4025) BN 59
J 2
(125 4035);
DISPLAY 0.617021 (125 4035);
PAINT PINK (125 4035);
FORCEPROP 2 LAST CDS_LIB mstr_standard
J 2
(125 4025);
DISPLAY 0.787234 (125 4025);
PAINT MONO (125 4025);
DISPLAY INVISIBLE (125 4025);
FORCEPROP 1 LAST BODY_TYPE PLUMBING
J 2
(125 3975);
DISPLAY 1.234043 (125 3975);
PAINT GREEN (125 3975);
DISPLAY INVISIBLE (125 3975);
FORCEPROP 1 LAST HDL_TAP TRUE
J 2
(-200 3900);
DISPLAY 1.234043 (-200 3900);
PAINT GREEN (-200 3900);
DISPLAY INVISIBLE (-200 3900);
FORCEPROP 1 LAST PATH I137
J 2
(127 4025);
DISPLAY 0.872340 (127 4025);
PAINT GREEN (127 4025);
DISPLAY INVISIBLE (127 4025);
FORCEADD TAP..6
R 2
(125 4125);
FORCEPROP 3 LASTPIN (75 4125) SIG_NAME M_G_DQ<61>
J 0
(85 4135);
DISPLAY 0.659574 (85 4135);
PAINT MONO (85 4135);
DISPLAY INVISIBLE (85 4135);
FORCEPROP 1 LASTPIN (75 4125) BN 61
J 2
(125 4135);
DISPLAY 0.617021 (125 4135);
PAINT PINK (125 4135);
FORCEPROP 2 LAST CDS_LIB mstr_standard
J 2
(125 4125);
DISPLAY 0.787234 (125 4125);
PAINT MONO (125 4125);
DISPLAY INVISIBLE (125 4125);
FORCEPROP 1 LAST BODY_TYPE PLUMBING
J 2
(125 4075);
DISPLAY 1.234043 (125 4075);
PAINT GREEN (125 4075);
DISPLAY INVISIBLE (125 4075);
FORCEPROP 1 LAST HDL_TAP TRUE
J 2
(-200 4000);
DISPLAY 1.234043 (-200 4000);
PAINT GREEN (-200 4000);
DISPLAY INVISIBLE (-200 4000);
FORCEPROP 1 LAST PATH I138
J 2
(127 4125);
DISPLAY 0.872340 (127 4125);
PAINT GREEN (127 4125);
DISPLAY INVISIBLE (127 4125);
FORCEADD TAP..6
R 2
(125 4075);
FORCEPROP 3 LASTPIN (75 4075) SIG_NAME M_G_DQ<60>
J 0
(85 4085);
DISPLAY 0.659574 (85 4085);
PAINT MONO (85 4085);
DISPLAY INVISIBLE (85 4085);
FORCEPROP 1 LASTPIN (75 4075) BN 60
J 2
(125 4085);
DISPLAY 0.617021 (125 4085);
PAINT PINK (125 4085);
FORCEPROP 2 LAST CDS_LIB mstr_standard
J 2
(125 4075);
DISPLAY 0.787234 (125 4075);
PAINT MONO (125 4075);
DISPLAY INVISIBLE (125 4075);
FORCEPROP 1 LAST BODY_TYPE PLUMBING
J 2
(125 4025);
DISPLAY 1.234043 (125 4025);
PAINT GREEN (125 4025);
DISPLAY INVISIBLE (125 4025);
FORCEPROP 1 LAST HDL_TAP TRUE
J 2
(-200 3950);
DISPLAY 1.234043 (-200 3950);
PAINT GREEN (-200 3950);
DISPLAY INVISIBLE (-200 3950);
FORCEPROP 1 LAST PATH I139
J 2
(127 4075);
DISPLAY 0.872340 (127 4075);
PAINT GREEN (127 4075);
DISPLAY INVISIBLE (127 4075);
FORCEADD OFFPAGE..1
(-2025 2125);
FORCEPROP 2 LAST $XR0 55 
J 0
(-2246 2125);
DISPLAY 0.638298 (-2246 2125);
PAINT MONO (-2246 2125);
FORCEPROP 2 LAST $XR1 77 
J 0
(-2336 2125);
DISPLAY 0.638298 (-2336 2125);
PAINT MONO (-2336 2125);
FORCEPROP 2 LAST $XR2 79 
J 0
(-2426 2125);
DISPLAY 0.638298 (-2426 2125);
PAINT MONO (-2426 2125);
FORCEPROP 2 LAST $XR3 80 
J 0
(-2516 2125);
DISPLAY 0.638298 (-2516 2125);
PAINT MONO (-2516 2125);
FORCEPROP 2 LAST $XR4 81 
J 0
(-2606 2125);
DISPLAY 0.638298 (-2606 2125);
PAINT MONO (-2606 2125);
FORCEPROP 2 LAST $XR5 82 
J 0
(-2696 2125);
DISPLAY 0.638298 (-2696 2125);
PAINT MONO (-2696 2125);
FORCEPROP 2 LAST CDS_LIB mstr_standard
J 0
(-2025 2125);
DISPLAY 0.787234 (-2025 2125);
PAINT MONO (-2025 2125);
DISPLAY INVISIBLE (-2025 2125);
FORCEPROP 1 LAST OFFPAGE TRUE
J 0
(-1700 2000);
DISPLAY 0.936170 (-1700 2000);
PAINT GREEN (-1700 2000);
DISPLAY INVISIBLE (-1700 2000);
FORCEPROP 1 LAST COMMENT_BODY TRUE
J 0
(-1900 2025);
DISPLAY 0.936170 (-1900 2025);
PAINT GREEN (-1900 2025);
DISPLAY INVISIBLE (-1900 2025);
FORCEPROP 2 LAST PATH I14
J 0
(-2225 2175);
DISPLAY 1.021277 (-2225 2175);
PAINT ORANGE (-2225 2175);
DISPLAY INVISIBLE (-2225 2175);
FORCEADD TAP..6
R 2
(125 4175);
FORCEPROP 3 LASTPIN (75 4175) SIG_NAME M_G_DQ<62>
J 0
(85 4185);
DISPLAY 0.659574 (85 4185);
PAINT MONO (85 4185);
DISPLAY INVISIBLE (85 4185);
FORCEPROP 1 LASTPIN (75 4175) BN 62
J 2
(125 4185);
DISPLAY 0.617021 (125 4185);
PAINT PINK (125 4185);
FORCEPROP 2 LAST CDS_LIB mstr_standard
J 2
(125 4175);
DISPLAY 0.787234 (125 4175);
PAINT MONO (125 4175);
DISPLAY INVISIBLE (125 4175);
FORCEPROP 1 LAST BODY_TYPE PLUMBING
J 2
(125 4125);
DISPLAY 1.234043 (125 4125);
PAINT GREEN (125 4125);
DISPLAY INVISIBLE (125 4125);
FORCEPROP 1 LAST HDL_TAP TRUE
J 2
(-200 4050);
DISPLAY 1.234043 (-200 4050);
PAINT GREEN (-200 4050);
DISPLAY INVISIBLE (-200 4050);
FORCEPROP 1 LAST PATH I140
J 2
(127 4175);
DISPLAY 0.872340 (127 4175);
PAINT GREEN (127 4175);
DISPLAY INVISIBLE (127 4175);
FORCEADD TAP..6
R 2
(125 4225);
FORCEPROP 3 LASTPIN (75 4225) SIG_NAME M_G_DQ<63>
J 0
(85 4235);
DISPLAY 0.659574 (85 4235);
PAINT MONO (85 4235);
DISPLAY INVISIBLE (85 4235);
FORCEPROP 1 LASTPIN (75 4225) BN 63
J 2
(125 4235);
DISPLAY 0.617021 (125 4235);
PAINT PINK (125 4235);
FORCEPROP 2 LAST CDS_LIB mstr_standard
J 2
(125 4225);
DISPLAY 0.787234 (125 4225);
PAINT MONO (125 4225);
DISPLAY INVISIBLE (125 4225);
FORCEPROP 1 LAST BODY_TYPE PLUMBING
J 2
(125 4175);
DISPLAY 1.234043 (125 4175);
PAINT GREEN (125 4175);
DISPLAY INVISIBLE (125 4175);
FORCEPROP 1 LAST HDL_TAP TRUE
J 2
(-200 4100);
DISPLAY 1.234043 (-200 4100);
PAINT GREEN (-200 4100);
DISPLAY INVISIBLE (-200 4100);
FORCEPROP 1 LAST PATH I141
J 2
(127 4225);
DISPLAY 0.872340 (127 4225);
PAINT GREEN (127 4225);
DISPLAY INVISIBLE (127 4225);
FORCEADD OFFPAGE..3
(675 4275);
FORCEPROP 2 LAST $XR0 57 
J 0
(889 4275);
DISPLAY 0.638298 (889 4275);
PAINT MONO (889 4275);
FORCEPROP 2 LAST $XR1 77 
J 0
(979 4275);
DISPLAY 0.638298 (979 4275);
PAINT MONO (979 4275);
FORCEPROP 2 LAST CDS_LIB mstr_standard
J 0
(675 4275);
DISPLAY 0.787234 (675 4275);
PAINT MONO (675 4275);
DISPLAY INVISIBLE (675 4275);
FORCEPROP 1 LAST OFFPAGE TRUE
J 0
(1000 4150);
DISPLAY 0.936170 (1000 4150);
PAINT GREEN (1000 4150);
DISPLAY INVISIBLE (1000 4150);
FORCEPROP 1 LAST COMMENT_BODY TRUE
J 0
(625 4175);
DISPLAY 0.936170 (625 4175);
PAINT GREEN (625 4175);
DISPLAY INVISIBLE (625 4175);
FORCEPROP 2 LAST PATH I142
J 0
(900 4325);
DISPLAY 1.021277 (900 4325);
PAINT ORANGE (900 4325);
DISPLAY INVISIBLE (900 4325);
FORCEADD GND..1
R 2
(2850 700);
FORCEPROP 3 LASTPIN (2850 750) SIG_NAME GND\g
J 0
(2860 760);
DISPLAY 0.659574 (2860 760);
PAINT MONO (2860 760);
DISPLAY INVISIBLE (2860 760);
FORCEPROP 1 LAST VOLTAGE 0.0V
J 2
(2895 657);
DISPLAY 0.340426 (2895 657);
PAINT SKYBLUE (2895 657);
DISPLAY INVISIBLE (2895 657);
FORCEPROP 1 LAST SIZE 1B
J 2
(2775 650);
DISPLAY 1.170213 (2775 650);
PAINT GREEN (2775 650);
DISPLAY INVISIBLE (2775 650);
FORCEPROP 2 LAST CDS_LIB mstr_symbols
J 0
(2850 700);
DISPLAY 0.787234 (2850 700);
PAINT MONO (2850 700);
DISPLAY INVISIBLE (2850 700);
FORCEPROP 2 LAST BOM_COST MEM
J 0
(2850 705);
PAINT ORANGE (2850 705);
DISPLAY INVISIBLE (2850 705);
FORCEPROP 1 LAST BODY_TYPE PLUMBING
J 2
(2895 657);
DISPLAY 0.340426 (2895 657);
PAINT GREEN (2895 657);
DISPLAY INVISIBLE (2895 657);
FORCEPROP 1 LAST PATH I143
J 2
(2775 700);
DISPLAY 0.872340 (2775 700);
PAINT AQUA (2775 700);
DISPLAY INVISIBLE (2775 700);
FORCEPROP 2 LAST ROOM DDR4_GH_G
J 0
(2850 705);
PAINT ORANGE (2850 705);
DISPLAY INVISIBLE (2850 705);
FORCEPROP 1 LAST HDL_POWER GND
J 2
(2850 850);
DISPLAY 0.553191 (2850 850);
PAINT GREEN (2850 850);
DISPLAY INVISIBLE (2850 850);
FORCEADD SCONN288_H44441003..3
(3550 2000);
FORCEPROP 1 LAST LOCATION J9T1
J 0
(3100 3400);
DISPLAY 0.617021 (3100 3400);
PAINT AQUA (3100 3400);
FORCEPROP 1 LAST PART_NUMBER H44441-003
J 0
(3100 650);
DISPLAY 0.617021 (3100 650);
PAINT BLUE (3100 650);
FORCEPROP 1 LAST MATERIAL SCONN
J 0
(3100 3350);
DISPLAY 0.617021 (3100 3350);
PAINT SKYBLUE (3100 3350);
FORCEPROP 2 LASTPIN (3050 3150) $PN 2
J 2
(3040 3160);
DISPLAY 0.617021 (3040 3160);
PAINT ORANGE (3040 3160);
FORCEPROP 2 LASTPIN (3050 3100) $PN 4
J 2
(3040 3110);
DISPLAY 0.617021 (3040 3110);
PAINT ORANGE (3040 3110);
FORCEPROP 2 LASTPIN (3050 3050) $PN 6
J 2
(3040 3060);
DISPLAY 0.617021 (3040 3060);
PAINT ORANGE (3040 3060);
FORCEPROP 2 LASTPIN (3050 3000) $PN 9
J 2
(3040 3010);
DISPLAY 0.617021 (3040 3010);
PAINT ORANGE (3040 3010);
FORCEPROP 2 LASTPIN (3050 2950) $PN 11
J 2
(3040 2960);
DISPLAY 0.617021 (3040 2960);
PAINT ORANGE (3040 2960);
FORCEPROP 2 LASTPIN (3050 2900) $PN 13
J 2
(3040 2910);
DISPLAY 0.617021 (3040 2910);
PAINT ORANGE (3040 2910);
FORCEPROP 2 LASTPIN (3050 2850) $PN 15
J 2
(3040 2860);
DISPLAY 0.617021 (3040 2860);
PAINT ORANGE (3040 2860);
FORCEPROP 2 LASTPIN (3050 2800) $PN 17
J 2
(3040 2810);
DISPLAY 0.617021 (3040 2810);
PAINT ORANGE (3040 2810);
FORCEPROP 2 LASTPIN (3050 2750) $PN 20
J 2
(3040 2760);
DISPLAY 0.617021 (3040 2760);
PAINT ORANGE (3040 2760);
FORCEPROP 2 LASTPIN (3050 2700) $PN 22
J 2
(3040 2710);
DISPLAY 0.617021 (3040 2710);
PAINT ORANGE (3040 2710);
FORCEPROP 2 LASTPIN (3050 2650) $PN 24
J 2
(3040 2660);
DISPLAY 0.617021 (3040 2660);
PAINT ORANGE (3040 2660);
FORCEPROP 2 LASTPIN (3050 2600) $PN 26
J 2
(3040 2610);
DISPLAY 0.617021 (3040 2610);
PAINT ORANGE (3040 2610);
FORCEPROP 2 LASTPIN (3050 2550) $PN 28
J 2
(3040 2560);
DISPLAY 0.617021 (3040 2560);
PAINT ORANGE (3040 2560);
FORCEPROP 2 LASTPIN (3050 2500) $PN 31
J 2
(3040 2510);
DISPLAY 0.617021 (3040 2510);
PAINT ORANGE (3040 2510);
FORCEPROP 2 LASTPIN (3050 2450) $PN 33
J 2
(3040 2460);
DISPLAY 0.617021 (3040 2460);
PAINT ORANGE (3040 2460);
FORCEPROP 2 LASTPIN (3050 2400) $PN 35
J 2
(3040 2410);
DISPLAY 0.617021 (3040 2410);
PAINT ORANGE (3040 2410);
FORCEPROP 2 LASTPIN (3050 2350) $PN 37
J 2
(3040 2360);
DISPLAY 0.617021 (3040 2360);
PAINT ORANGE (3040 2360);
FORCEPROP 2 LASTPIN (3050 2300) $PN 39
J 2
(3040 2310);
DISPLAY 0.617021 (3040 2310);
PAINT ORANGE (3040 2310);
FORCEPROP 2 LASTPIN (3050 2250) $PN 42
J 2
(3040 2260);
DISPLAY 0.617021 (3040 2260);
PAINT ORANGE (3040 2260);
FORCEPROP 2 LASTPIN (3050 2200) $PN 44
J 2
(3040 2210);
DISPLAY 0.617021 (3040 2210);
PAINT ORANGE (3040 2210);
FORCEPROP 2 LASTPIN (3050 2150) $PN 46
J 2
(3040 2160);
DISPLAY 0.617021 (3040 2160);
PAINT ORANGE (3040 2160);
FORCEPROP 2 LASTPIN (3050 2100) $PN 48
J 2
(3040 2110);
DISPLAY 0.617021 (3040 2110);
PAINT ORANGE (3040 2110);
FORCEPROP 2 LASTPIN (3050 2050) $PN 50
J 2
(3040 2060);
DISPLAY 0.617021 (3040 2060);
PAINT ORANGE (3040 2060);
FORCEPROP 2 LASTPIN (3050 2000) $PN 53
J 2
(3040 2010);
DISPLAY 0.617021 (3040 2010);
PAINT ORANGE (3040 2010);
FORCEPROP 2 LASTPIN (3050 1950) $PN 55
J 2
(3040 1960);
DISPLAY 0.617021 (3040 1960);
PAINT ORANGE (3040 1960);
FORCEPROP 2 LASTPIN (3050 1900) $PN 57
J 2
(3040 1910);
DISPLAY 0.617021 (3040 1910);
PAINT ORANGE (3040 1910);
FORCEPROP 2 LASTPIN (3050 1850) $PN 94
J 2
(3040 1860);
DISPLAY 0.617021 (3040 1860);
PAINT ORANGE (3040 1860);
FORCEPROP 2 LASTPIN (3050 1800) $PN 96
J 2
(3040 1810);
DISPLAY 0.617021 (3040 1810);
PAINT ORANGE (3040 1810);
FORCEPROP 2 LASTPIN (3050 1750) $PN 98
J 2
(3040 1760);
DISPLAY 0.617021 (3040 1760);
PAINT ORANGE (3040 1760);
FORCEPROP 2 LASTPIN (3050 1700) $PN 101
J 2
(3040 1710);
DISPLAY 0.617021 (3040 1710);
PAINT ORANGE (3040 1710);
FORCEPROP 2 LASTPIN (3050 1650) $PN 103
J 2
(3040 1660);
DISPLAY 0.617021 (3040 1660);
PAINT ORANGE (3040 1660);
FORCEPROP 2 LASTPIN (3050 1600) $PN 105
J 2
(3040 1610);
DISPLAY 0.617021 (3040 1610);
PAINT ORANGE (3040 1610);
FORCEPROP 2 LASTPIN (3050 1550) $PN 107
J 2
(3040 1560);
DISPLAY 0.617021 (3040 1560);
PAINT ORANGE (3040 1560);
FORCEPROP 2 LASTPIN (3050 1500) $PN 109
J 2
(3040 1510);
DISPLAY 0.617021 (3040 1510);
PAINT ORANGE (3040 1510);
FORCEPROP 2 LASTPIN (3050 1450) $PN 112
J 2
(3040 1460);
DISPLAY 0.617021 (3040 1460);
PAINT ORANGE (3040 1460);
FORCEPROP 2 LASTPIN (3050 1400) $PN 114
J 2
(3040 1410);
DISPLAY 0.617021 (3040 1410);
PAINT ORANGE (3040 1410);
FORCEPROP 2 LASTPIN (3050 1350) $PN 116
J 2
(3040 1360);
DISPLAY 0.617021 (3040 1360);
PAINT ORANGE (3040 1360);
FORCEPROP 2 LASTPIN (3050 1300) $PN 118
J 2
(3040 1310);
DISPLAY 0.617021 (3040 1310);
PAINT ORANGE (3040 1310);
FORCEPROP 2 LASTPIN (3050 1250) $PN 120
J 2
(3040 1260);
DISPLAY 0.617021 (3040 1260);
PAINT ORANGE (3040 1260);
FORCEPROP 2 LASTPIN (3050 1200) $PN 123
J 2
(3040 1210);
DISPLAY 0.617021 (3040 1210);
PAINT ORANGE (3040 1210);
FORCEPROP 2 LASTPIN (3050 1150) $PN 125
J 2
(3040 1160);
DISPLAY 0.617021 (3040 1160);
PAINT ORANGE (3040 1160);
FORCEPROP 2 LASTPIN (3050 1100) $PN 127
J 2
(3040 1110);
DISPLAY 0.617021 (3040 1110);
PAINT ORANGE (3040 1110);
FORCEPROP 2 LASTPIN (3050 1050) $PN 129
J 2
(3040 1060);
DISPLAY 0.617021 (3040 1060);
PAINT ORANGE (3040 1060);
FORCEPROP 2 LASTPIN (3050 1000) $PN 131
J 2
(3040 1010);
DISPLAY 0.617021 (3040 1010);
PAINT ORANGE (3040 1010);
FORCEPROP 2 LASTPIN (3050 950) $PN 134
J 2
(3040 960);
DISPLAY 0.617021 (3040 960);
PAINT ORANGE (3040 960);
FORCEPROP 2 LASTPIN (3050 900) $PN 136
J 2
(3040 910);
DISPLAY 0.617021 (3040 910);
PAINT ORANGE (3040 910);
FORCEPROP 2 LASTPIN (3050 850) $PN 138
J 2
(3040 860);
DISPLAY 0.617021 (3040 860);
PAINT ORANGE (3040 860);
FORCEPROP 2 LASTPIN (4050 3150) $PN 147
J 0
(4060 3160);
DISPLAY 0.617021 (4060 3160);
PAINT ORANGE (4060 3160);
FORCEPROP 2 LASTPIN (4050 3100) $PN 149
J 0
(4060 3110);
DISPLAY 0.617021 (4060 3110);
PAINT ORANGE (4060 3110);
FORCEPROP 2 LASTPIN (4050 3050) $PN 151
J 0
(4060 3060);
DISPLAY 0.617021 (4060 3060);
PAINT ORANGE (4060 3060);
FORCEPROP 2 LASTPIN (4050 3000) $PN 154
J 0
(4060 3010);
DISPLAY 0.617021 (4060 3010);
PAINT ORANGE (4060 3010);
FORCEPROP 2 LASTPIN (4050 2950) $PN 156
J 0
(4060 2960);
DISPLAY 0.617021 (4060 2960);
PAINT ORANGE (4060 2960);
FORCEPROP 2 LASTPIN (4050 2900) $PN 158
J 0
(4060 2910);
DISPLAY 0.617021 (4060 2910);
PAINT ORANGE (4060 2910);
FORCEPROP 2 LASTPIN (4050 2850) $PN 160
J 0
(4060 2860);
DISPLAY 0.617021 (4060 2860);
PAINT ORANGE (4060 2860);
FORCEPROP 2 LASTPIN (4050 2800) $PN 162
J 0
(4060 2810);
DISPLAY 0.617021 (4060 2810);
PAINT ORANGE (4060 2810);
FORCEPROP 2 LASTPIN (4050 2750) $PN 165
J 0
(4060 2760);
DISPLAY 0.617021 (4060 2760);
PAINT ORANGE (4060 2760);
FORCEPROP 2 LASTPIN (4050 2700) $PN 167
J 0
(4060 2710);
DISPLAY 0.617021 (4060 2710);
PAINT ORANGE (4060 2710);
FORCEPROP 2 LASTPIN (4050 2650) $PN 169
J 0
(4060 2660);
DISPLAY 0.617021 (4060 2660);
PAINT ORANGE (4060 2660);
FORCEPROP 2 LASTPIN (4050 2600) $PN 171
J 0
(4060 2610);
DISPLAY 0.617021 (4060 2610);
PAINT ORANGE (4060 2610);
FORCEPROP 2 LASTPIN (4050 2550) $PN 173
J 0
(4060 2560);
DISPLAY 0.617021 (4060 2560);
PAINT ORANGE (4060 2560);
FORCEPROP 2 LASTPIN (4050 2500) $PN 176
J 0
(4060 2510);
DISPLAY 0.617021 (4060 2510);
PAINT ORANGE (4060 2510);
FORCEPROP 2 LASTPIN (4050 2450) $PN 178
J 0
(4060 2460);
DISPLAY 0.617021 (4060 2460);
PAINT ORANGE (4060 2460);
FORCEPROP 2 LASTPIN (4050 2400) $PN 180
J 0
(4060 2410);
DISPLAY 0.617021 (4060 2410);
PAINT ORANGE (4060 2410);
FORCEPROP 2 LASTPIN (4050 2350) $PN 182
J 0
(4060 2360);
DISPLAY 0.617021 (4060 2360);
PAINT ORANGE (4060 2360);
FORCEPROP 2 LASTPIN (4050 2300) $PN 184
J 0
(4060 2310);
DISPLAY 0.617021 (4060 2310);
PAINT ORANGE (4060 2310);
FORCEPROP 2 LASTPIN (4050 2250) $PN 187
J 0
(4060 2260);
DISPLAY 0.617021 (4060 2260);
PAINT ORANGE (4060 2260);
FORCEPROP 2 LASTPIN (4050 2200) $PN 189
J 0
(4060 2210);
DISPLAY 0.617021 (4060 2210);
PAINT ORANGE (4060 2210);
FORCEPROP 2 LASTPIN (4050 2150) $PN 191
J 0
(4060 2160);
DISPLAY 0.617021 (4060 2160);
PAINT ORANGE (4060 2160);
FORCEPROP 2 LASTPIN (4050 2100) $PN 193
J 0
(4060 2110);
DISPLAY 0.617021 (4060 2110);
PAINT ORANGE (4060 2110);
FORCEPROP 2 LASTPIN (4050 2050) $PN 195
J 0
(4060 2060);
DISPLAY 0.617021 (4060 2060);
PAINT ORANGE (4060 2060);
FORCEPROP 2 LASTPIN (4050 2000) $PN 198
J 0
(4060 2010);
DISPLAY 0.617021 (4060 2010);
PAINT ORANGE (4060 2010);
FORCEPROP 2 LASTPIN (4050 1950) $PN 200
J 0
(4060 1960);
DISPLAY 0.617021 (4060 1960);
PAINT ORANGE (4060 1960);
FORCEPROP 2 LASTPIN (4050 1900) $PN 202
J 0
(4060 1910);
DISPLAY 0.617021 (4060 1910);
PAINT ORANGE (4060 1910);
FORCEPROP 2 LASTPIN (4050 1850) $PN 239
J 0
(4060 1860);
DISPLAY 0.617021 (4060 1860);
PAINT ORANGE (4060 1860);
FORCEPROP 2 LASTPIN (4050 1800) $PN 241
J 0
(4060 1810);
DISPLAY 0.617021 (4060 1810);
PAINT ORANGE (4060 1810);
FORCEPROP 2 LASTPIN (4050 1750) $PN 243
J 0
(4060 1760);
DISPLAY 0.617021 (4060 1760);
PAINT ORANGE (4060 1760);
FORCEPROP 2 LASTPIN (4050 1700) $PN 246
J 0
(4060 1710);
DISPLAY 0.617021 (4060 1710);
PAINT ORANGE (4060 1710);
FORCEPROP 2 LASTPIN (4050 1650) $PN 248
J 0
(4060 1660);
DISPLAY 0.617021 (4060 1660);
PAINT ORANGE (4060 1660);
FORCEPROP 2 LASTPIN (4050 1600) $PN 250
J 0
(4060 1610);
DISPLAY 0.617021 (4060 1610);
PAINT ORANGE (4060 1610);
FORCEPROP 2 LASTPIN (4050 1550) $PN 252
J 0
(4060 1560);
DISPLAY 0.617021 (4060 1560);
PAINT ORANGE (4060 1560);
FORCEPROP 2 LASTPIN (4050 1500) $PN 254
J 0
(4060 1510);
DISPLAY 0.617021 (4060 1510);
PAINT ORANGE (4060 1510);
FORCEPROP 2 LASTPIN (4050 1450) $PN 257
J 0
(4060 1460);
DISPLAY 0.617021 (4060 1460);
PAINT ORANGE (4060 1460);
FORCEPROP 2 LASTPIN (4050 1400) $PN 259
J 0
(4060 1410);
DISPLAY 0.617021 (4060 1410);
PAINT ORANGE (4060 1410);
FORCEPROP 2 LASTPIN (4050 1350) $PN 261
J 0
(4060 1360);
DISPLAY 0.617021 (4060 1360);
PAINT ORANGE (4060 1360);
FORCEPROP 2 LASTPIN (4050 1300) $PN 263
J 0
(4060 1310);
DISPLAY 0.617021 (4060 1310);
PAINT ORANGE (4060 1310);
FORCEPROP 2 LASTPIN (4050 1250) $PN 265
J 0
(4060 1260);
DISPLAY 0.617021 (4060 1260);
PAINT ORANGE (4060 1260);
FORCEPROP 2 LASTPIN (4050 1200) $PN 268
J 0
(4060 1210);
DISPLAY 0.617021 (4060 1210);
PAINT ORANGE (4060 1210);
FORCEPROP 2 LASTPIN (4050 1150) $PN 270
J 0
(4060 1160);
DISPLAY 0.617021 (4060 1160);
PAINT ORANGE (4060 1160);
FORCEPROP 2 LASTPIN (4050 1100) $PN 272
J 0
(4060 1110);
DISPLAY 0.617021 (4060 1110);
PAINT ORANGE (4060 1110);
FORCEPROP 2 LASTPIN (4050 1050) $PN 274
J 0
(4060 1060);
DISPLAY 0.617021 (4060 1060);
PAINT ORANGE (4060 1060);
FORCEPROP 2 LASTPIN (4050 1000) $PN 276
J 0
(4060 1010);
DISPLAY 0.617021 (4060 1010);
PAINT ORANGE (4060 1010);
FORCEPROP 2 LASTPIN (4050 950) $PN 279
J 0
(4060 960);
DISPLAY 0.617021 (4060 960);
PAINT ORANGE (4060 960);
FORCEPROP 2 LASTPIN (4050 900) $PN 281
J 0
(4060 910);
DISPLAY 0.617021 (4060 910);
PAINT ORANGE (4060 910);
FORCEPROP 2 LASTPIN (4050 850) $PN 283
J 0
(4060 860);
DISPLAY 0.617021 (4060 860);
PAINT ORANGE (4060 860);
FORCEPROP 1 LAST PACK_TYPE PIP
J 0
(3100 3450);
PAINT SKYBLUE (3100 3450);
DISPLAY INVISIBLE (3100 3450);
FORCEPROP 2 LAST BOM_COST MEM
J 0
(3550 2000);
PAINT ORANGE (3550 2000);
DISPLAY INVISIBLE (3550 2000);
FORCEPROP 2 LAST CDS_LIB mstr_sconn
J 0
(3550 2000);
PAINT ORANGE (3550 2000);
DISPLAY INVISIBLE (3550 2000);
FORCEPROP 2 LAST SEC_TYPE PIP
J 0
(3100 3450);
DISPLAY 1.021277 (3100 3450);
PAINT ORANGE (3100 3450);
DISPLAY INVISIBLE (3100 3450);
FORCEPROP 2 LAST SEC 3
J 0
(3100 3450);
DISPLAY 0.680851 (3100 3450);
PAINT MONO (3100 3450);
DISPLAY INVISIBLE (3100 3450);
FORCEPROP 2 LAST CDS_LOCATION J9T1
J 0
(3100 3400);
DISPLAY 0.617021 (3100 3400);
PAINT AQUA (3100 3400);
DISPLAY INVISIBLE (3100 3400);
FORCEPROP 1 LAST PATH I144
J 0
(3550 3350);
PAINT GREEN (3550 3350);
DISPLAY INVISIBLE (3550 3350);
FORCEPROP 2 LAST ROOM DDR4_GH_G
J 0
(3550 2000);
PAINT ORANGE (3550 2000);
DISPLAY INVISIBLE (3550 2000);
FORCEADD TAP..6
R 2
(2450 3250);
FORCEPROP 3 LASTPIN (2400 3250) SIG_NAME M_G_DQS_DP<1>
J 0
(2410 3260);
DISPLAY 0.659574 (2410 3260);
PAINT MONO (2410 3260);
DISPLAY INVISIBLE (2410 3260);
FORCEPROP 1 LASTPIN (2400 3250) BN 1
J 2
(2450 3260);
DISPLAY 0.617021 (2450 3260);
PAINT PINK (2450 3260);
FORCEPROP 2 LAST CDS_LIB mstr_standard
J 0
(2450 3250);
DISPLAY 0.787234 (2450 3250);
PAINT MONO (2450 3250);
DISPLAY INVISIBLE (2450 3250);
FORCEPROP 1 LAST BODY_TYPE PLUMBING
J 2
(2450 3200);
DISPLAY 1.234043 (2450 3200);
PAINT GREEN (2450 3200);
DISPLAY INVISIBLE (2450 3200);
FORCEPROP 1 LAST HDL_TAP TRUE
J 2
(2125 3125);
DISPLAY 1.234043 (2125 3125);
PAINT GREEN (2125 3125);
DISPLAY INVISIBLE (2125 3125);
FORCEPROP 1 LAST PATH I148
J 2
(2452 3250);
DISPLAY 0.872340 (2452 3250);
PAINT GREEN (2452 3250);
DISPLAY INVISIBLE (2452 3250);
FORCEADD TAP..6
R 2
(2450 3150);
FORCEPROP 3 LASTPIN (2400 3150) SIG_NAME M_G_DQS_DP<0>
J 0
(2410 3160);
DISPLAY 0.659574 (2410 3160);
PAINT MONO (2410 3160);
DISPLAY INVISIBLE (2410 3160);
FORCEPROP 1 LASTPIN (2400 3150) BN 0
J 2
(2450 3160);
DISPLAY 0.617021 (2450 3160);
PAINT PINK (2450 3160);
FORCEPROP 2 LAST CDS_LIB mstr_standard
J 0
(2450 3150);
DISPLAY 0.787234 (2450 3150);
PAINT MONO (2450 3150);
DISPLAY INVISIBLE (2450 3150);
FORCEPROP 1 LAST BODY_TYPE PLUMBING
J 2
(2450 3100);
DISPLAY 1.234043 (2450 3100);
PAINT GREEN (2450 3100);
DISPLAY INVISIBLE (2450 3100);
FORCEPROP 1 LAST HDL_TAP TRUE
J 2
(2125 3025);
DISPLAY 1.234043 (2125 3025);
PAINT GREEN (2125 3025);
DISPLAY INVISIBLE (2125 3025);
FORCEPROP 1 LAST PATH I149
J 2
(2452 3150);
DISPLAY 0.872340 (2452 3150);
PAINT GREEN (2452 3150);
DISPLAY INVISIBLE (2452 3150);
FORCEADD OFFPAGE..6
(-2025 2225);
FORCEPROP 2 LAST $XR0 57 
J 0
(-2274 2225);
DISPLAY 0.638298 (-2274 2225);
PAINT MONO (-2274 2225);
FORCEPROP 2 LAST $XR1 77 
J 0
(-2364 2225);
DISPLAY 0.638298 (-2364 2225);
PAINT MONO (-2364 2225);
FORCEPROP 2 LAST CDS_LIB mstr_standard
J 0
(-2025 2225);
DISPLAY 0.787234 (-2025 2225);
PAINT MONO (-2025 2225);
DISPLAY INVISIBLE (-2025 2225);
FORCEPROP 1 LAST OFFPAGE TRUE
J 0
(-1700 2100);
DISPLAY 0.936170 (-1700 2100);
PAINT GREEN (-1700 2100);
DISPLAY INVISIBLE (-1700 2100);
FORCEPROP 1 LAST COMMENT_BODY TRUE
J 0
(-1925 2150);
DISPLAY 0.936170 (-1925 2150);
PAINT GREEN (-1925 2150);
DISPLAY INVISIBLE (-1925 2150);
FORCEPROP 2 LAST PATH I15
J 0
(-2250 2275);
DISPLAY 1.021277 (-2250 2275);
PAINT ORANGE (-2250 2275);
DISPLAY INVISIBLE (-2250 2275);
FORCEADD TAP..6
R 2
(2450 3350);
FORCEPROP 3 LASTPIN (2400 3350) SIG_NAME M_G_DQS_DP<2>
J 0
(2410 3360);
DISPLAY 0.659574 (2410 3360);
PAINT MONO (2410 3360);
DISPLAY INVISIBLE (2410 3360);
FORCEPROP 1 LASTPIN (2400 3350) BN 2
J 2
(2450 3360);
DISPLAY 0.617021 (2450 3360);
PAINT PINK (2450 3360);
FORCEPROP 2 LAST CDS_LIB mstr_standard
J 0
(2450 3350);
DISPLAY 0.787234 (2450 3350);
PAINT MONO (2450 3350);
DISPLAY INVISIBLE (2450 3350);
FORCEPROP 1 LAST BODY_TYPE PLUMBING
J 2
(2450 3300);
DISPLAY 1.234043 (2450 3300);
PAINT GREEN (2450 3300);
DISPLAY INVISIBLE (2450 3300);
FORCEPROP 1 LAST HDL_TAP TRUE
J 2
(2125 3225);
DISPLAY 1.234043 (2125 3225);
PAINT GREEN (2125 3225);
DISPLAY INVISIBLE (2125 3225);
FORCEPROP 1 LAST PATH I150
J 2
(2452 3350);
DISPLAY 0.872340 (2452 3350);
PAINT GREEN (2452 3350);
DISPLAY INVISIBLE (2452 3350);
FORCEADD TAP..6
R 2
(2650 3100);
FORCEPROP 3 LASTPIN (2600 3100) SIG_NAME M_G_DQS_DN<0>
J 0
(2610 3110);
DISPLAY 0.659574 (2610 3110);
PAINT MONO (2610 3110);
DISPLAY INVISIBLE (2610 3110);
FORCEPROP 1 LASTPIN (2600 3100) BN 0
J 2
(2650 3110);
DISPLAY 0.617021 (2650 3110);
PAINT PINK (2650 3110);
FORCEPROP 2 LAST CDS_LIB mstr_standard
J 0
(2650 3100);
DISPLAY 0.787234 (2650 3100);
PAINT MONO (2650 3100);
DISPLAY INVISIBLE (2650 3100);
FORCEPROP 1 LAST BODY_TYPE PLUMBING
J 2
(2650 3050);
DISPLAY 1.234043 (2650 3050);
PAINT GREEN (2650 3050);
DISPLAY INVISIBLE (2650 3050);
FORCEPROP 1 LAST HDL_TAP TRUE
J 2
(2325 2975);
DISPLAY 1.234043 (2325 2975);
PAINT GREEN (2325 2975);
DISPLAY INVISIBLE (2325 2975);
FORCEPROP 1 LAST PATH I151
J 2
(2652 3100);
DISPLAY 0.872340 (2652 3100);
PAINT GREEN (2652 3100);
DISPLAY INVISIBLE (2652 3100);
FORCEADD TAP..6
R 2
(2650 3200);
FORCEPROP 3 LASTPIN (2600 3200) SIG_NAME M_G_DQS_DN<1>
J 0
(2610 3210);
DISPLAY 0.659574 (2610 3210);
PAINT MONO (2610 3210);
DISPLAY INVISIBLE (2610 3210);
FORCEPROP 1 LASTPIN (2600 3200) BN 1
J 2
(2650 3210);
DISPLAY 0.617021 (2650 3210);
PAINT PINK (2650 3210);
FORCEPROP 2 LAST CDS_LIB mstr_standard
J 0
(2650 3200);
DISPLAY 0.787234 (2650 3200);
PAINT MONO (2650 3200);
DISPLAY INVISIBLE (2650 3200);
FORCEPROP 1 LAST BODY_TYPE PLUMBING
J 2
(2650 3150);
DISPLAY 1.234043 (2650 3150);
PAINT GREEN (2650 3150);
DISPLAY INVISIBLE (2650 3150);
FORCEPROP 1 LAST HDL_TAP TRUE
J 2
(2325 3075);
DISPLAY 1.234043 (2325 3075);
PAINT GREEN (2325 3075);
DISPLAY INVISIBLE (2325 3075);
FORCEPROP 1 LAST PATH I152
J 2
(2652 3200);
DISPLAY 0.872340 (2652 3200);
PAINT GREEN (2652 3200);
DISPLAY INVISIBLE (2652 3200);
FORCEADD TAP..6
R 2
(2650 3300);
FORCEPROP 3 LASTPIN (2600 3300) SIG_NAME M_G_DQS_DN<2>
J 0
(2610 3310);
DISPLAY 0.659574 (2610 3310);
PAINT MONO (2610 3310);
DISPLAY INVISIBLE (2610 3310);
FORCEPROP 1 LASTPIN (2600 3300) BN 2
J 2
(2650 3310);
DISPLAY 0.617021 (2650 3310);
PAINT PINK (2650 3310);
FORCEPROP 2 LAST CDS_LIB mstr_standard
J 0
(2650 3300);
DISPLAY 0.787234 (2650 3300);
PAINT MONO (2650 3300);
DISPLAY INVISIBLE (2650 3300);
FORCEPROP 1 LAST BODY_TYPE PLUMBING
J 2
(2650 3250);
DISPLAY 1.234043 (2650 3250);
PAINT GREEN (2650 3250);
DISPLAY INVISIBLE (2650 3250);
FORCEPROP 1 LAST HDL_TAP TRUE
J 2
(2325 3175);
DISPLAY 1.234043 (2325 3175);
PAINT GREEN (2325 3175);
DISPLAY INVISIBLE (2325 3175);
FORCEPROP 1 LAST PATH I153
J 2
(2652 3300);
DISPLAY 0.872340 (2652 3300);
PAINT GREEN (2652 3300);
DISPLAY INVISIBLE (2652 3300);
FORCEADD TAP..6
R 2
(2450 3450);
FORCEPROP 3 LASTPIN (2400 3450) SIG_NAME M_G_DQS_DP<3>
J 0
(2410 3460);
DISPLAY 0.659574 (2410 3460);
PAINT MONO (2410 3460);
DISPLAY INVISIBLE (2410 3460);
FORCEPROP 1 LASTPIN (2400 3450) BN 3
J 2
(2450 3460);
DISPLAY 0.617021 (2450 3460);
PAINT PINK (2450 3460);
FORCEPROP 2 LAST CDS_LIB mstr_standard
J 0
(2450 3450);
DISPLAY 0.787234 (2450 3450);
PAINT MONO (2450 3450);
DISPLAY INVISIBLE (2450 3450);
FORCEPROP 1 LAST BODY_TYPE PLUMBING
J 2
(2450 3400);
DISPLAY 1.234043 (2450 3400);
PAINT GREEN (2450 3400);
DISPLAY INVISIBLE (2450 3400);
FORCEPROP 1 LAST HDL_TAP TRUE
J 2
(2125 3325);
DISPLAY 1.234043 (2125 3325);
PAINT GREEN (2125 3325);
DISPLAY INVISIBLE (2125 3325);
FORCEPROP 1 LAST PATH I154
J 2
(2452 3450);
DISPLAY 0.872340 (2452 3450);
PAINT GREEN (2452 3450);
DISPLAY INVISIBLE (2452 3450);
FORCEADD TAP..6
R 2
(2450 3550);
FORCEPROP 3 LASTPIN (2400 3550) SIG_NAME M_G_DQS_DP<4>
J 0
(2410 3560);
DISPLAY 0.659574 (2410 3560);
PAINT MONO (2410 3560);
DISPLAY INVISIBLE (2410 3560);
FORCEPROP 1 LASTPIN (2400 3550) BN 4
J 2
(2450 3560);
DISPLAY 0.617021 (2450 3560);
PAINT PINK (2450 3560);
FORCEPROP 2 LAST CDS_LIB mstr_standard
J 0
(2450 3550);
DISPLAY 0.787234 (2450 3550);
PAINT MONO (2450 3550);
DISPLAY INVISIBLE (2450 3550);
FORCEPROP 1 LAST BODY_TYPE PLUMBING
J 2
(2450 3500);
DISPLAY 1.234043 (2450 3500);
PAINT GREEN (2450 3500);
DISPLAY INVISIBLE (2450 3500);
FORCEPROP 1 LAST HDL_TAP TRUE
J 2
(2125 3425);
DISPLAY 1.234043 (2125 3425);
PAINT GREEN (2125 3425);
DISPLAY INVISIBLE (2125 3425);
FORCEPROP 1 LAST PATH I155
J 2
(2452 3550);
DISPLAY 0.872340 (2452 3550);
PAINT GREEN (2452 3550);
DISPLAY INVISIBLE (2452 3550);
FORCEADD TAP..6
R 2
(2450 3750);
FORCEPROP 3 LASTPIN (2400 3750) SIG_NAME M_G_DQS_DP<6>
J 0
(2410 3760);
DISPLAY 0.659574 (2410 3760);
PAINT MONO (2410 3760);
DISPLAY INVISIBLE (2410 3760);
FORCEPROP 1 LASTPIN (2400 3750) BN 6
J 2
(2450 3760);
DISPLAY 0.617021 (2450 3760);
PAINT PINK (2450 3760);
FORCEPROP 2 LAST CDS_LIB mstr_standard
J 0
(2450 3750);
DISPLAY 0.787234 (2450 3750);
PAINT MONO (2450 3750);
DISPLAY INVISIBLE (2450 3750);
FORCEPROP 1 LAST BODY_TYPE PLUMBING
J 2
(2450 3700);
DISPLAY 1.234043 (2450 3700);
PAINT GREEN (2450 3700);
DISPLAY INVISIBLE (2450 3700);
FORCEPROP 1 LAST HDL_TAP TRUE
J 2
(2125 3625);
DISPLAY 1.234043 (2125 3625);
PAINT GREEN (2125 3625);
DISPLAY INVISIBLE (2125 3625);
FORCEPROP 1 LAST PATH I156
J 2
(2452 3750);
DISPLAY 0.872340 (2452 3750);
PAINT GREEN (2452 3750);
DISPLAY INVISIBLE (2452 3750);
FORCEADD TAP..6
R 2
(2450 3650);
FORCEPROP 3 LASTPIN (2400 3650) SIG_NAME M_G_DQS_DP<5>
J 0
(2410 3660);
DISPLAY 0.659574 (2410 3660);
PAINT MONO (2410 3660);
DISPLAY INVISIBLE (2410 3660);
FORCEPROP 1 LASTPIN (2400 3650) BN 5
J 2
(2450 3660);
DISPLAY 0.617021 (2450 3660);
PAINT PINK (2450 3660);
FORCEPROP 2 LAST CDS_LIB mstr_standard
J 0
(2450 3650);
DISPLAY 0.787234 (2450 3650);
PAINT MONO (2450 3650);
DISPLAY INVISIBLE (2450 3650);
FORCEPROP 1 LAST BODY_TYPE PLUMBING
J 2
(2450 3600);
DISPLAY 1.234043 (2450 3600);
PAINT GREEN (2450 3600);
DISPLAY INVISIBLE (2450 3600);
FORCEPROP 1 LAST HDL_TAP TRUE
J 2
(2125 3525);
DISPLAY 1.234043 (2125 3525);
PAINT GREEN (2125 3525);
DISPLAY INVISIBLE (2125 3525);
FORCEPROP 1 LAST PATH I157
J 2
(2452 3650);
DISPLAY 0.872340 (2452 3650);
PAINT GREEN (2452 3650);
DISPLAY INVISIBLE (2452 3650);
FORCEADD TAP..6
R 2
(2450 3850);
FORCEPROP 3 LASTPIN (2400 3850) SIG_NAME M_G_DQS_DP<7>
J 0
(2410 3860);
DISPLAY 0.659574 (2410 3860);
PAINT MONO (2410 3860);
DISPLAY INVISIBLE (2410 3860);
FORCEPROP 1 LASTPIN (2400 3850) BN 7
J 2
(2450 3860);
DISPLAY 0.617021 (2450 3860);
PAINT PINK (2450 3860);
FORCEPROP 2 LAST CDS_LIB mstr_standard
J 0
(2450 3850);
DISPLAY 0.787234 (2450 3850);
PAINT MONO (2450 3850);
DISPLAY INVISIBLE (2450 3850);
FORCEPROP 1 LAST BODY_TYPE PLUMBING
J 2
(2450 3800);
DISPLAY 1.234043 (2450 3800);
PAINT GREEN (2450 3800);
DISPLAY INVISIBLE (2450 3800);
FORCEPROP 1 LAST HDL_TAP TRUE
J 2
(2125 3725);
DISPLAY 1.234043 (2125 3725);
PAINT GREEN (2125 3725);
DISPLAY INVISIBLE (2125 3725);
FORCEPROP 1 LAST PATH I158
J 2
(2452 3850);
DISPLAY 0.872340 (2452 3850);
PAINT GREEN (2452 3850);
DISPLAY INVISIBLE (2452 3850);
FORCEADD TAP..6
R 2
(2650 3500);
FORCEPROP 3 LASTPIN (2600 3500) SIG_NAME M_G_DQS_DN<4>
J 0
(2610 3510);
DISPLAY 0.659574 (2610 3510);
PAINT MONO (2610 3510);
DISPLAY INVISIBLE (2610 3510);
FORCEPROP 1 LASTPIN (2600 3500) BN 4
J 2
(2650 3510);
DISPLAY 0.617021 (2650 3510);
PAINT PINK (2650 3510);
FORCEPROP 2 LAST CDS_LIB mstr_standard
J 0
(2650 3500);
DISPLAY 0.787234 (2650 3500);
PAINT MONO (2650 3500);
DISPLAY INVISIBLE (2650 3500);
FORCEPROP 1 LAST BODY_TYPE PLUMBING
J 2
(2650 3450);
DISPLAY 1.234043 (2650 3450);
PAINT GREEN (2650 3450);
DISPLAY INVISIBLE (2650 3450);
FORCEPROP 1 LAST HDL_TAP TRUE
J 2
(2325 3375);
DISPLAY 1.234043 (2325 3375);
PAINT GREEN (2325 3375);
DISPLAY INVISIBLE (2325 3375);
FORCEPROP 1 LAST PATH I159
J 2
(2652 3500);
DISPLAY 0.872340 (2652 3500);
PAINT GREEN (2652 3500);
DISPLAY INVISIBLE (2652 3500);
FORCEADD OFFPAGE..1
(-2025 2175);
FORCEPROP 2 LAST $XR0 57 
J 0
(-2276 2175);
DISPLAY 0.638298 (-2276 2175);
PAINT MONO (-2276 2175);
FORCEPROP 2 LAST $XR1 77 
J 0
(-2366 2175);
DISPLAY 0.638298 (-2366 2175);
PAINT MONO (-2366 2175);
FORCEPROP 2 LAST CDS_LIB mstr_standard
J 0
(-2025 2175);
DISPLAY 0.787234 (-2025 2175);
PAINT MONO (-2025 2175);
DISPLAY INVISIBLE (-2025 2175);
FORCEPROP 1 LAST OFFPAGE TRUE
J 0
(-1700 2050);
DISPLAY 0.936170 (-1700 2050);
PAINT GREEN (-1700 2050);
DISPLAY INVISIBLE (-1700 2050);
FORCEPROP 1 LAST COMMENT_BODY TRUE
J 0
(-1900 2075);
DISPLAY 0.936170 (-1900 2075);
PAINT GREEN (-1900 2075);
DISPLAY INVISIBLE (-1900 2075);
FORCEPROP 2 LAST PATH I16
J 0
(-2275 2225);
DISPLAY 1.021277 (-2275 2225);
PAINT ORANGE (-2275 2225);
DISPLAY INVISIBLE (-2275 2225);
FORCEADD TAP..6
R 2
(2650 3400);
FORCEPROP 3 LASTPIN (2600 3400) SIG_NAME M_G_DQS_DN<3>
J 0
(2610 3410);
DISPLAY 0.659574 (2610 3410);
PAINT MONO (2610 3410);
DISPLAY INVISIBLE (2610 3410);
FORCEPROP 1 LASTPIN (2600 3400) BN 3
J 2
(2650 3410);
DISPLAY 0.617021 (2650 3410);
PAINT PINK (2650 3410);
FORCEPROP 2 LAST CDS_LIB mstr_standard
J 0
(2650 3400);
DISPLAY 0.787234 (2650 3400);
PAINT MONO (2650 3400);
DISPLAY INVISIBLE (2650 3400);
FORCEPROP 1 LAST BODY_TYPE PLUMBING
J 2
(2650 3350);
DISPLAY 1.234043 (2650 3350);
PAINT GREEN (2650 3350);
DISPLAY INVISIBLE (2650 3350);
FORCEPROP 1 LAST HDL_TAP TRUE
J 2
(2325 3275);
DISPLAY 1.234043 (2325 3275);
PAINT GREEN (2325 3275);
DISPLAY INVISIBLE (2325 3275);
FORCEPROP 1 LAST PATH I160
J 2
(2652 3400);
DISPLAY 0.872340 (2652 3400);
PAINT GREEN (2652 3400);
DISPLAY INVISIBLE (2652 3400);
FORCEADD TAP..6
R 2
(2650 3600);
FORCEPROP 3 LASTPIN (2600 3600) SIG_NAME M_G_DQS_DN<5>
J 0
(2610 3610);
DISPLAY 0.659574 (2610 3610);
PAINT MONO (2610 3610);
DISPLAY INVISIBLE (2610 3610);
FORCEPROP 1 LASTPIN (2600 3600) BN 5
J 2
(2650 3610);
DISPLAY 0.617021 (2650 3610);
PAINT PINK (2650 3610);
FORCEPROP 2 LAST CDS_LIB mstr_standard
J 0
(2650 3600);
DISPLAY 0.787234 (2650 3600);
PAINT MONO (2650 3600);
DISPLAY INVISIBLE (2650 3600);
FORCEPROP 1 LAST BODY_TYPE PLUMBING
J 2
(2650 3550);
DISPLAY 1.234043 (2650 3550);
PAINT GREEN (2650 3550);
DISPLAY INVISIBLE (2650 3550);
FORCEPROP 1 LAST HDL_TAP TRUE
J 2
(2325 3475);
DISPLAY 1.234043 (2325 3475);
PAINT GREEN (2325 3475);
DISPLAY INVISIBLE (2325 3475);
FORCEPROP 1 LAST PATH I161
J 2
(2652 3600);
DISPLAY 0.872340 (2652 3600);
PAINT GREEN (2652 3600);
DISPLAY INVISIBLE (2652 3600);
FORCEADD TAP..6
R 2
(2650 3800);
FORCEPROP 3 LASTPIN (2600 3800) SIG_NAME M_G_DQS_DN<7>
J 0
(2610 3810);
DISPLAY 0.659574 (2610 3810);
PAINT MONO (2610 3810);
DISPLAY INVISIBLE (2610 3810);
FORCEPROP 1 LASTPIN (2600 3800) BN 7
J 2
(2650 3810);
DISPLAY 0.617021 (2650 3810);
PAINT PINK (2650 3810);
FORCEPROP 2 LAST CDS_LIB mstr_standard
J 0
(2650 3800);
DISPLAY 0.787234 (2650 3800);
PAINT MONO (2650 3800);
DISPLAY INVISIBLE (2650 3800);
FORCEPROP 1 LAST BODY_TYPE PLUMBING
J 2
(2650 3750);
DISPLAY 1.234043 (2650 3750);
PAINT GREEN (2650 3750);
DISPLAY INVISIBLE (2650 3750);
FORCEPROP 1 LAST HDL_TAP TRUE
J 2
(2325 3675);
DISPLAY 1.234043 (2325 3675);
PAINT GREEN (2325 3675);
DISPLAY INVISIBLE (2325 3675);
FORCEPROP 1 LAST PATH I162
J 2
(2652 3800);
DISPLAY 0.872340 (2652 3800);
PAINT GREEN (2652 3800);
DISPLAY INVISIBLE (2652 3800);
FORCEADD TAP..6
R 2
(2650 3700);
FORCEPROP 3 LASTPIN (2600 3700) SIG_NAME M_G_DQS_DN<6>
J 0
(2610 3710);
DISPLAY 0.659574 (2610 3710);
PAINT MONO (2610 3710);
DISPLAY INVISIBLE (2610 3710);
FORCEPROP 1 LASTPIN (2600 3700) BN 6
J 2
(2650 3710);
DISPLAY 0.617021 (2650 3710);
PAINT PINK (2650 3710);
FORCEPROP 2 LAST CDS_LIB mstr_standard
J 0
(2650 3700);
DISPLAY 0.787234 (2650 3700);
PAINT MONO (2650 3700);
DISPLAY INVISIBLE (2650 3700);
FORCEPROP 1 LAST BODY_TYPE PLUMBING
J 2
(2650 3650);
DISPLAY 1.234043 (2650 3650);
PAINT GREEN (2650 3650);
DISPLAY INVISIBLE (2650 3650);
FORCEPROP 1 LAST HDL_TAP TRUE
J 2
(2325 3575);
DISPLAY 1.234043 (2325 3575);
PAINT GREEN (2325 3575);
DISPLAY INVISIBLE (2325 3575);
FORCEPROP 1 LAST PATH I163
J 2
(2652 3700);
DISPLAY 0.872340 (2652 3700);
PAINT GREEN (2652 3700);
DISPLAY INVISIBLE (2652 3700);
FORCEADD GND..1
R 2
(4250 700);
FORCEPROP 3 LASTPIN (4250 750) SIG_NAME GND\g
J 0
(4260 760);
DISPLAY 0.659574 (4260 760);
PAINT MONO (4260 760);
DISPLAY INVISIBLE (4260 760);
FORCEPROP 1 LAST VOLTAGE 0.0V
J 2
(4295 657);
DISPLAY 0.340426 (4295 657);
PAINT SKYBLUE (4295 657);
DISPLAY INVISIBLE (4295 657);
FORCEPROP 1 LAST SIZE 1B
J 2
(4175 650);
DISPLAY 1.170213 (4175 650);
PAINT GREEN (4175 650);
DISPLAY INVISIBLE (4175 650);
FORCEPROP 2 LAST CDS_LIB mstr_symbols
J 0
(4250 700);
DISPLAY 0.787234 (4250 700);
PAINT MONO (4250 700);
DISPLAY INVISIBLE (4250 700);
FORCEPROP 2 LAST BOM_COST MEM
J 0
(4250 705);
PAINT ORANGE (4250 705);
DISPLAY INVISIBLE (4250 705);
FORCEPROP 1 LAST BODY_TYPE PLUMBING
J 2
(4295 657);
DISPLAY 0.340426 (4295 657);
PAINT GREEN (4295 657);
DISPLAY INVISIBLE (4295 657);
FORCEPROP 1 LAST PATH I164
J 2
(4175 700);
DISPLAY 0.872340 (4175 700);
PAINT AQUA (4175 700);
DISPLAY INVISIBLE (4175 700);
FORCEPROP 2 LAST ROOM DDR4_GH_G
J 0
(4250 705);
PAINT ORANGE (4250 705);
DISPLAY INVISIBLE (4250 705);
FORCEPROP 1 LAST HDL_POWER GND
J 2
(4250 850);
DISPLAY 0.553191 (4250 850);
PAINT GREEN (4250 850);
DISPLAY INVISIBLE (4250 850);
FORCEADD TAP..6
R 2
(2450 3950);
FORCEPROP 3 LASTPIN (2400 3950) SIG_NAME M_G_DQS_DP<8>
J 0
(2410 3960);
DISPLAY 0.659574 (2410 3960);
PAINT MONO (2410 3960);
DISPLAY INVISIBLE (2410 3960);
FORCEPROP 1 LASTPIN (2400 3950) BN 8
J 2
(2450 3960);
DISPLAY 0.617021 (2450 3960);
PAINT PINK (2450 3960);
FORCEPROP 2 LAST CDS_LIB mstr_standard
J 0
(2450 3950);
DISPLAY 0.787234 (2450 3950);
PAINT MONO (2450 3950);
DISPLAY INVISIBLE (2450 3950);
FORCEPROP 1 LAST BODY_TYPE PLUMBING
J 2
(2450 3900);
DISPLAY 1.234043 (2450 3900);
PAINT GREEN (2450 3900);
DISPLAY INVISIBLE (2450 3900);
FORCEPROP 1 LAST HDL_TAP TRUE
J 2
(2125 3825);
DISPLAY 1.234043 (2125 3825);
PAINT GREEN (2125 3825);
DISPLAY INVISIBLE (2125 3825);
FORCEPROP 1 LAST PATH I165
J 2
(2452 3950);
DISPLAY 0.872340 (2452 3950);
PAINT GREEN (2452 3950);
DISPLAY INVISIBLE (2452 3950);
FORCEADD TAP..6
R 2
(2450 4150);
FORCEPROP 3 LASTPIN (2400 4150) SIG_NAME M_G_DQS_DP<10>
J 0
(2410 4160);
DISPLAY 0.659574 (2410 4160);
PAINT MONO (2410 4160);
DISPLAY INVISIBLE (2410 4160);
FORCEPROP 1 LASTPIN (2400 4150) BN 10
J 2
(2450 4160);
DISPLAY 0.617021 (2450 4160);
PAINT PINK (2450 4160);
FORCEPROP 2 LAST CDS_LIB mstr_standard
J 0
(2450 4150);
DISPLAY 0.787234 (2450 4150);
PAINT MONO (2450 4150);
DISPLAY INVISIBLE (2450 4150);
FORCEPROP 1 LAST BODY_TYPE PLUMBING
J 2
(2450 4100);
DISPLAY 1.234043 (2450 4100);
PAINT GREEN (2450 4100);
DISPLAY INVISIBLE (2450 4100);
FORCEPROP 1 LAST HDL_TAP TRUE
J 2
(2125 4025);
DISPLAY 1.234043 (2125 4025);
PAINT GREEN (2125 4025);
DISPLAY INVISIBLE (2125 4025);
FORCEPROP 1 LAST PATH I166
J 2
(2452 4150);
DISPLAY 0.872340 (2452 4150);
PAINT GREEN (2452 4150);
DISPLAY INVISIBLE (2452 4150);
FORCEADD TAP..6
R 2
(2450 4050);
FORCEPROP 3 LASTPIN (2400 4050) SIG_NAME M_G_DQS_DP<9>
J 0
(2410 4060);
DISPLAY 0.659574 (2410 4060);
PAINT MONO (2410 4060);
DISPLAY INVISIBLE (2410 4060);
FORCEPROP 1 LASTPIN (2400 4050) BN 9
J 2
(2450 4060);
DISPLAY 0.617021 (2450 4060);
PAINT PINK (2450 4060);
FORCEPROP 2 LAST CDS_LIB mstr_standard
J 0
(2450 4050);
DISPLAY 0.787234 (2450 4050);
PAINT MONO (2450 4050);
DISPLAY INVISIBLE (2450 4050);
FORCEPROP 1 LAST BODY_TYPE PLUMBING
J 2
(2450 4000);
DISPLAY 1.234043 (2450 4000);
PAINT GREEN (2450 4000);
DISPLAY INVISIBLE (2450 4000);
FORCEPROP 1 LAST HDL_TAP TRUE
J 2
(2125 3925);
DISPLAY 1.234043 (2125 3925);
PAINT GREEN (2125 3925);
DISPLAY INVISIBLE (2125 3925);
FORCEPROP 1 LAST PATH I167
J 2
(2452 4050);
DISPLAY 0.872340 (2452 4050);
PAINT GREEN (2452 4050);
DISPLAY INVISIBLE (2452 4050);
FORCEADD TAP..6
R 2
(2450 4250);
FORCEPROP 3 LASTPIN (2400 4250) SIG_NAME M_G_DQS_DP<11>
J 0
(2410 4260);
DISPLAY 0.659574 (2410 4260);
PAINT MONO (2410 4260);
DISPLAY INVISIBLE (2410 4260);
FORCEPROP 1 LASTPIN (2400 4250) BN 11
J 2
(2450 4260);
DISPLAY 0.617021 (2450 4260);
PAINT PINK (2450 4260);
FORCEPROP 2 LAST CDS_LIB mstr_standard
J 0
(2450 4250);
DISPLAY 0.787234 (2450 4250);
PAINT MONO (2450 4250);
DISPLAY INVISIBLE (2450 4250);
FORCEPROP 1 LAST BODY_TYPE PLUMBING
J 2
(2450 4200);
DISPLAY 1.234043 (2450 4200);
PAINT GREEN (2450 4200);
DISPLAY INVISIBLE (2450 4200);
FORCEPROP 1 LAST HDL_TAP TRUE
J 2
(2125 4125);
DISPLAY 1.234043 (2125 4125);
PAINT GREEN (2125 4125);
DISPLAY INVISIBLE (2125 4125);
FORCEPROP 1 LAST PATH I168
J 2
(2452 4250);
DISPLAY 0.872340 (2452 4250);
PAINT GREEN (2452 4250);
DISPLAY INVISIBLE (2452 4250);
FORCEADD TAP..6
R 2
(2450 4350);
FORCEPROP 3 LASTPIN (2400 4350) SIG_NAME M_G_DQS_DP<12>
J 0
(2410 4360);
DISPLAY 0.659574 (2410 4360);
PAINT MONO (2410 4360);
DISPLAY INVISIBLE (2410 4360);
FORCEPROP 1 LASTPIN (2400 4350) BN 12
J 2
(2450 4360);
DISPLAY 0.617021 (2450 4360);
PAINT PINK (2450 4360);
FORCEPROP 2 LAST CDS_LIB mstr_standard
J 0
(2450 4350);
DISPLAY 0.787234 (2450 4350);
PAINT MONO (2450 4350);
DISPLAY INVISIBLE (2450 4350);
FORCEPROP 1 LAST BODY_TYPE PLUMBING
J 2
(2450 4300);
DISPLAY 1.234043 (2450 4300);
PAINT GREEN (2450 4300);
DISPLAY INVISIBLE (2450 4300);
FORCEPROP 1 LAST HDL_TAP TRUE
J 2
(2125 4225);
DISPLAY 1.234043 (2125 4225);
PAINT GREEN (2125 4225);
DISPLAY INVISIBLE (2125 4225);
FORCEPROP 1 LAST PATH I169
J 2
(2452 4350);
DISPLAY 0.872340 (2452 4350);
PAINT GREEN (2452 4350);
DISPLAY INVISIBLE (2452 4350);
FORCEADD OFFPAGE..1
(-2025 2375);
FORCEPROP 2 LAST $XR0 57 
J 0
(-2246 2375);
DISPLAY 0.638298 (-2246 2375);
PAINT MONO (-2246 2375);
FORCEPROP 2 LAST $XR1 77 
J 0
(-2336 2375);
DISPLAY 0.638298 (-2336 2375);
PAINT MONO (-2336 2375);
FORCEPROP 2 LAST CDS_LIB mstr_standard
J 0
(-2025 2375);
DISPLAY 0.787234 (-2025 2375);
PAINT MONO (-2025 2375);
DISPLAY INVISIBLE (-2025 2375);
FORCEPROP 1 LAST OFFPAGE TRUE
J 0
(-1700 2250);
DISPLAY 0.936170 (-1700 2250);
PAINT GREEN (-1700 2250);
DISPLAY INVISIBLE (-1700 2250);
FORCEPROP 1 LAST COMMENT_BODY TRUE
J 0
(-1900 2275);
DISPLAY 0.936170 (-1900 2275);
PAINT GREEN (-1900 2275);
DISPLAY INVISIBLE (-1900 2275);
FORCEPROP 2 LAST PATH I17
J 0
(-2225 2425);
DISPLAY 1.021277 (-2225 2425);
PAINT ORANGE (-2225 2425);
DISPLAY INVISIBLE (-2225 2425);
FORCEADD TAP..6
R 2
(2650 4000);
FORCEPROP 3 LASTPIN (2600 4000) SIG_NAME M_G_DQS_DN<9>
J 0
(2610 4010);
DISPLAY 0.659574 (2610 4010);
PAINT MONO (2610 4010);
DISPLAY INVISIBLE (2610 4010);
FORCEPROP 1 LASTPIN (2600 4000) BN 9
J 2
(2650 4010);
DISPLAY 0.617021 (2650 4010);
PAINT PINK (2650 4010);
FORCEPROP 2 LAST CDS_LIB mstr_standard
J 0
(2650 4000);
DISPLAY 0.787234 (2650 4000);
PAINT MONO (2650 4000);
DISPLAY INVISIBLE (2650 4000);
FORCEPROP 1 LAST BODY_TYPE PLUMBING
J 2
(2650 3950);
DISPLAY 1.234043 (2650 3950);
PAINT GREEN (2650 3950);
DISPLAY INVISIBLE (2650 3950);
FORCEPROP 1 LAST HDL_TAP TRUE
J 2
(2325 3875);
DISPLAY 1.234043 (2325 3875);
PAINT GREEN (2325 3875);
DISPLAY INVISIBLE (2325 3875);
FORCEPROP 1 LAST PATH I170
J 2
(2652 4000);
DISPLAY 0.872340 (2652 4000);
PAINT GREEN (2652 4000);
DISPLAY INVISIBLE (2652 4000);
FORCEADD TAP..6
R 2
(2650 4100);
FORCEPROP 3 LASTPIN (2600 4100) SIG_NAME M_G_DQS_DN<10>
J 0
(2610 4110);
DISPLAY 0.659574 (2610 4110);
PAINT MONO (2610 4110);
DISPLAY INVISIBLE (2610 4110);
FORCEPROP 1 LASTPIN (2600 4100) BN 10
J 2
(2650 4110);
DISPLAY 0.617021 (2650 4110);
PAINT PINK (2650 4110);
FORCEPROP 2 LAST CDS_LIB mstr_standard
J 0
(2650 4100);
DISPLAY 0.787234 (2650 4100);
PAINT MONO (2650 4100);
DISPLAY INVISIBLE (2650 4100);
FORCEPROP 1 LAST BODY_TYPE PLUMBING
J 2
(2650 4050);
DISPLAY 1.234043 (2650 4050);
PAINT GREEN (2650 4050);
DISPLAY INVISIBLE (2650 4050);
FORCEPROP 1 LAST HDL_TAP TRUE
J 2
(2325 3975);
DISPLAY 1.234043 (2325 3975);
PAINT GREEN (2325 3975);
DISPLAY INVISIBLE (2325 3975);
FORCEPROP 1 LAST PATH I171
J 2
(2652 4100);
DISPLAY 0.872340 (2652 4100);
PAINT GREEN (2652 4100);
DISPLAY INVISIBLE (2652 4100);
FORCEADD TAP..6
R 2
(2650 3900);
FORCEPROP 3 LASTPIN (2600 3900) SIG_NAME M_G_DQS_DN<8>
J 0
(2610 3910);
DISPLAY 0.659574 (2610 3910);
PAINT MONO (2610 3910);
DISPLAY INVISIBLE (2610 3910);
FORCEPROP 1 LASTPIN (2600 3900) BN 8
J 2
(2650 3910);
DISPLAY 0.617021 (2650 3910);
PAINT PINK (2650 3910);
FORCEPROP 2 LAST CDS_LIB mstr_standard
J 0
(2650 3900);
DISPLAY 0.787234 (2650 3900);
PAINT MONO (2650 3900);
DISPLAY INVISIBLE (2650 3900);
FORCEPROP 1 LAST BODY_TYPE PLUMBING
J 2
(2650 3850);
DISPLAY 1.234043 (2650 3850);
PAINT GREEN (2650 3850);
DISPLAY INVISIBLE (2650 3850);
FORCEPROP 1 LAST HDL_TAP TRUE
J 2
(2325 3775);
DISPLAY 1.234043 (2325 3775);
PAINT GREEN (2325 3775);
DISPLAY INVISIBLE (2325 3775);
FORCEPROP 1 LAST PATH I172
J 2
(2652 3900);
DISPLAY 0.872340 (2652 3900);
PAINT GREEN (2652 3900);
DISPLAY INVISIBLE (2652 3900);
FORCEADD TAP..6
R 2
(2650 4200);
FORCEPROP 3 LASTPIN (2600 4200) SIG_NAME M_G_DQS_DN<11>
J 0
(2610 4210);
DISPLAY 0.659574 (2610 4210);
PAINT MONO (2610 4210);
DISPLAY INVISIBLE (2610 4210);
FORCEPROP 1 LASTPIN (2600 4200) BN 11
J 2
(2650 4210);
DISPLAY 0.617021 (2650 4210);
PAINT PINK (2650 4210);
FORCEPROP 2 LAST CDS_LIB mstr_standard
J 0
(2650 4200);
DISPLAY 0.787234 (2650 4200);
PAINT MONO (2650 4200);
DISPLAY INVISIBLE (2650 4200);
FORCEPROP 1 LAST BODY_TYPE PLUMBING
J 2
(2650 4150);
DISPLAY 1.234043 (2650 4150);
PAINT GREEN (2650 4150);
DISPLAY INVISIBLE (2650 4150);
FORCEPROP 1 LAST HDL_TAP TRUE
J 2
(2325 4075);
DISPLAY 1.234043 (2325 4075);
PAINT GREEN (2325 4075);
DISPLAY INVISIBLE (2325 4075);
FORCEPROP 1 LAST PATH I173
J 2
(2652 4200);
DISPLAY 0.872340 (2652 4200);
PAINT GREEN (2652 4200);
DISPLAY INVISIBLE (2652 4200);
FORCEADD TAP..6
R 2
(2650 4400);
FORCEPROP 3 LASTPIN (2600 4400) SIG_NAME M_G_DQS_DN<13>
J 0
(2610 4410);
DISPLAY 0.659574 (2610 4410);
PAINT MONO (2610 4410);
DISPLAY INVISIBLE (2610 4410);
FORCEPROP 1 LASTPIN (2600 4400) BN 13
J 2
(2650 4410);
DISPLAY 0.617021 (2650 4410);
PAINT PINK (2650 4410);
FORCEPROP 2 LAST CDS_LIB mstr_standard
J 0
(2650 4400);
DISPLAY 0.787234 (2650 4400);
PAINT MONO (2650 4400);
DISPLAY INVISIBLE (2650 4400);
FORCEPROP 1 LAST BODY_TYPE PLUMBING
J 2
(2650 4350);
DISPLAY 1.234043 (2650 4350);
PAINT GREEN (2650 4350);
DISPLAY INVISIBLE (2650 4350);
FORCEPROP 1 LAST HDL_TAP TRUE
J 2
(2325 4275);
DISPLAY 1.234043 (2325 4275);
PAINT GREEN (2325 4275);
DISPLAY INVISIBLE (2325 4275);
FORCEPROP 1 LAST PATH I174
J 2
(2652 4400);
DISPLAY 0.872340 (2652 4400);
PAINT GREEN (2652 4400);
DISPLAY INVISIBLE (2652 4400);
FORCEADD TAP..6
R 2
(2650 4300);
FORCEPROP 3 LASTPIN (2600 4300) SIG_NAME M_G_DQS_DN<12>
J 0
(2610 4310);
DISPLAY 0.659574 (2610 4310);
PAINT MONO (2610 4310);
DISPLAY INVISIBLE (2610 4310);
FORCEPROP 1 LASTPIN (2600 4300) BN 12
J 2
(2650 4310);
DISPLAY 0.617021 (2650 4310);
PAINT PINK (2650 4310);
FORCEPROP 2 LAST CDS_LIB mstr_standard
J 0
(2650 4300);
DISPLAY 0.787234 (2650 4300);
PAINT MONO (2650 4300);
DISPLAY INVISIBLE (2650 4300);
FORCEPROP 1 LAST BODY_TYPE PLUMBING
J 2
(2650 4250);
DISPLAY 1.234043 (2650 4250);
PAINT GREEN (2650 4250);
DISPLAY INVISIBLE (2650 4250);
FORCEPROP 1 LAST HDL_TAP TRUE
J 2
(2325 4175);
DISPLAY 1.234043 (2325 4175);
PAINT GREEN (2325 4175);
DISPLAY INVISIBLE (2325 4175);
FORCEPROP 1 LAST PATH I175
J 2
(2652 4300);
DISPLAY 0.872340 (2652 4300);
PAINT GREEN (2652 4300);
DISPLAY INVISIBLE (2652 4300);
FORCEADD TAP..6
R 2
(2450 4450);
FORCEPROP 3 LASTPIN (2400 4450) SIG_NAME M_G_DQS_DP<13>
J 0
(2410 4460);
DISPLAY 0.659574 (2410 4460);
PAINT MONO (2410 4460);
DISPLAY INVISIBLE (2410 4460);
FORCEPROP 1 LASTPIN (2400 4450) BN 13
J 2
(2450 4460);
DISPLAY 0.617021 (2450 4460);
PAINT PINK (2450 4460);
FORCEPROP 2 LAST CDS_LIB mstr_standard
J 0
(2450 4450);
DISPLAY 0.787234 (2450 4450);
PAINT MONO (2450 4450);
DISPLAY INVISIBLE (2450 4450);
FORCEPROP 1 LAST BODY_TYPE PLUMBING
J 2
(2450 4400);
DISPLAY 1.234043 (2450 4400);
PAINT GREEN (2450 4400);
DISPLAY INVISIBLE (2450 4400);
FORCEPROP 1 LAST HDL_TAP TRUE
J 2
(2125 4325);
DISPLAY 1.234043 (2125 4325);
PAINT GREEN (2125 4325);
DISPLAY INVISIBLE (2125 4325);
FORCEPROP 1 LAST PATH I176
J 2
(2452 4450);
DISPLAY 0.872340 (2452 4450);
PAINT GREEN (2452 4450);
DISPLAY INVISIBLE (2452 4450);
FORCEADD TAP..6
R 2
(2450 4550);
FORCEPROP 3 LASTPIN (2400 4550) SIG_NAME M_G_DQS_DP<14>
J 0
(2410 4560);
DISPLAY 0.659574 (2410 4560);
PAINT MONO (2410 4560);
DISPLAY INVISIBLE (2410 4560);
FORCEPROP 1 LASTPIN (2400 4550) BN 14
J 2
(2450 4560);
DISPLAY 0.617021 (2450 4560);
PAINT PINK (2450 4560);
FORCEPROP 2 LAST CDS_LIB mstr_standard
J 0
(2450 4550);
DISPLAY 0.787234 (2450 4550);
PAINT MONO (2450 4550);
DISPLAY INVISIBLE (2450 4550);
FORCEPROP 1 LAST BODY_TYPE PLUMBING
J 2
(2450 4500);
DISPLAY 1.234043 (2450 4500);
PAINT GREEN (2450 4500);
DISPLAY INVISIBLE (2450 4500);
FORCEPROP 1 LAST HDL_TAP TRUE
J 2
(2125 4425);
DISPLAY 1.234043 (2125 4425);
PAINT GREEN (2125 4425);
DISPLAY INVISIBLE (2125 4425);
FORCEPROP 1 LAST PATH I177
J 2
(2452 4550);
DISPLAY 0.872340 (2452 4550);
PAINT GREEN (2452 4550);
DISPLAY INVISIBLE (2452 4550);
FORCEADD TAP..6
R 2
(2450 4650);
FORCEPROP 3 LASTPIN (2400 4650) SIG_NAME M_G_DQS_DP<15>
J 0
(2410 4660);
DISPLAY 0.659574 (2410 4660);
PAINT MONO (2410 4660);
DISPLAY INVISIBLE (2410 4660);
FORCEPROP 1 LASTPIN (2400 4650) BN 15
J 2
(2450 4660);
DISPLAY 0.617021 (2450 4660);
PAINT PINK (2450 4660);
FORCEPROP 2 LAST CDS_LIB mstr_standard
J 0
(2450 4650);
DISPLAY 0.787234 (2450 4650);
PAINT MONO (2450 4650);
DISPLAY INVISIBLE (2450 4650);
FORCEPROP 1 LAST BODY_TYPE PLUMBING
J 2
(2450 4600);
DISPLAY 1.234043 (2450 4600);
PAINT GREEN (2450 4600);
DISPLAY INVISIBLE (2450 4600);
FORCEPROP 1 LAST HDL_TAP TRUE
J 2
(2125 4525);
DISPLAY 1.234043 (2125 4525);
PAINT GREEN (2125 4525);
DISPLAY INVISIBLE (2125 4525);
FORCEPROP 1 LAST PATH I178
J 2
(2452 4650);
DISPLAY 0.872340 (2452 4650);
PAINT GREEN (2452 4650);
DISPLAY INVISIBLE (2452 4650);
FORCEADD TAP..6
R 2
(2450 4750);
FORCEPROP 3 LASTPIN (2400 4750) SIG_NAME M_G_DQS_DP<16>
J 0
(2410 4760);
DISPLAY 0.659574 (2410 4760);
PAINT MONO (2410 4760);
DISPLAY INVISIBLE (2410 4760);
FORCEPROP 1 LASTPIN (2400 4750) BN 16
J 2
(2450 4760);
DISPLAY 0.617021 (2450 4760);
PAINT PINK (2450 4760);
FORCEPROP 2 LAST CDS_LIB mstr_standard
J 0
(2450 4750);
DISPLAY 0.787234 (2450 4750);
PAINT MONO (2450 4750);
DISPLAY INVISIBLE (2450 4750);
FORCEPROP 1 LAST BODY_TYPE PLUMBING
J 2
(2450 4700);
DISPLAY 1.234043 (2450 4700);
PAINT GREEN (2450 4700);
DISPLAY INVISIBLE (2450 4700);
FORCEPROP 1 LAST HDL_TAP TRUE
J 2
(2125 4625);
DISPLAY 1.234043 (2125 4625);
PAINT GREEN (2125 4625);
DISPLAY INVISIBLE (2125 4625);
FORCEPROP 1 LAST PATH I179
J 2
(2452 4750);
DISPLAY 0.872340 (2452 4750);
PAINT GREEN (2452 4750);
DISPLAY INVISIBLE (2452 4750);
FORCEADD OFFPAGE..1
(-2025 2525);
FORCEPROP 2 LAST $XR0 57 
J 0
(-2246 2525);
DISPLAY 0.638298 (-2246 2525);
PAINT MONO (-2246 2525);
FORCEPROP 2 LAST $XR1 77 
J 0
(-2336 2525);
DISPLAY 0.638298 (-2336 2525);
PAINT MONO (-2336 2525);
FORCEPROP 2 LAST CDS_LIB mstr_standard
J 0
(-2025 2525);
DISPLAY 0.787234 (-2025 2525);
PAINT MONO (-2025 2525);
DISPLAY INVISIBLE (-2025 2525);
FORCEPROP 1 LAST OFFPAGE TRUE
J 0
(-1700 2400);
DISPLAY 0.936170 (-1700 2400);
PAINT GREEN (-1700 2400);
DISPLAY INVISIBLE (-1700 2400);
FORCEPROP 1 LAST COMMENT_BODY TRUE
J 0
(-1900 2425);
DISPLAY 0.936170 (-1900 2425);
PAINT GREEN (-1900 2425);
DISPLAY INVISIBLE (-1900 2425);
FORCEPROP 2 LAST PATH I18
J 0
(-2225 2575);
DISPLAY 1.021277 (-2225 2575);
PAINT ORANGE (-2225 2575);
DISPLAY INVISIBLE (-2225 2575);
FORCEADD TAP..6
R 2
(2450 4850);
FORCEPROP 3 LASTPIN (2400 4850) SIG_NAME M_G_DQS_DP<17>
J 0
(2410 4860);
DISPLAY 0.659574 (2410 4860);
PAINT MONO (2410 4860);
DISPLAY INVISIBLE (2410 4860);
FORCEPROP 1 LASTPIN (2400 4850) BN 17
J 2
(2450 4860);
DISPLAY 0.617021 (2450 4860);
PAINT PINK (2450 4860);
FORCEPROP 2 LAST CDS_LIB mstr_standard
J 2
(2450 4850);
DISPLAY 0.787234 (2450 4850);
PAINT MONO (2450 4850);
DISPLAY INVISIBLE (2450 4850);
FORCEPROP 1 LAST BODY_TYPE PLUMBING
J 2
(2450 4800);
DISPLAY 1.234043 (2450 4800);
PAINT GREEN (2450 4800);
DISPLAY INVISIBLE (2450 4800);
FORCEPROP 1 LAST HDL_TAP TRUE
J 2
(2125 4725);
DISPLAY 1.234043 (2125 4725);
PAINT GREEN (2125 4725);
DISPLAY INVISIBLE (2125 4725);
FORCEPROP 1 LAST PATH I180
J 2
(2452 4850);
DISPLAY 0.872340 (2452 4850);
PAINT GREEN (2452 4850);
DISPLAY INVISIBLE (2452 4850);
FORCEADD TAP..6
R 2
(2650 4600);
FORCEPROP 3 LASTPIN (2600 4600) SIG_NAME M_G_DQS_DN<15>
J 0
(2610 4610);
DISPLAY 0.659574 (2610 4610);
PAINT MONO (2610 4610);
DISPLAY INVISIBLE (2610 4610);
FORCEPROP 1 LASTPIN (2600 4600) BN 15
J 2
(2650 4610);
DISPLAY 0.617021 (2650 4610);
PAINT PINK (2650 4610);
FORCEPROP 2 LAST CDS_LIB mstr_standard
J 0
(2650 4600);
DISPLAY 0.787234 (2650 4600);
PAINT MONO (2650 4600);
DISPLAY INVISIBLE (2650 4600);
FORCEPROP 1 LAST BODY_TYPE PLUMBING
J 2
(2650 4550);
DISPLAY 1.234043 (2650 4550);
PAINT GREEN (2650 4550);
DISPLAY INVISIBLE (2650 4550);
FORCEPROP 1 LAST HDL_TAP TRUE
J 2
(2325 4475);
DISPLAY 1.234043 (2325 4475);
PAINT GREEN (2325 4475);
DISPLAY INVISIBLE (2325 4475);
FORCEPROP 1 LAST PATH I181
J 2
(2652 4600);
DISPLAY 0.872340 (2652 4600);
PAINT GREEN (2652 4600);
DISPLAY INVISIBLE (2652 4600);
FORCEADD TAP..6
R 2
(2650 4500);
FORCEPROP 3 LASTPIN (2600 4500) SIG_NAME M_G_DQS_DN<14>
J 0
(2610 4510);
DISPLAY 0.659574 (2610 4510);
PAINT MONO (2610 4510);
DISPLAY INVISIBLE (2610 4510);
FORCEPROP 1 LASTPIN (2600 4500) BN 14
J 2
(2650 4510);
DISPLAY 0.617021 (2650 4510);
PAINT PINK (2650 4510);
FORCEPROP 2 LAST CDS_LIB mstr_standard
J 0
(2650 4500);
DISPLAY 0.787234 (2650 4500);
PAINT MONO (2650 4500);
DISPLAY INVISIBLE (2650 4500);
FORCEPROP 1 LAST BODY_TYPE PLUMBING
J 2
(2650 4450);
DISPLAY 1.234043 (2650 4450);
PAINT GREEN (2650 4450);
DISPLAY INVISIBLE (2650 4450);
FORCEPROP 1 LAST HDL_TAP TRUE
J 2
(2325 4375);
DISPLAY 1.234043 (2325 4375);
PAINT GREEN (2325 4375);
DISPLAY INVISIBLE (2325 4375);
FORCEPROP 1 LAST PATH I182
J 2
(2652 4500);
DISPLAY 0.872340 (2652 4500);
PAINT GREEN (2652 4500);
DISPLAY INVISIBLE (2652 4500);
FORCEADD TAP..6
R 2
(2650 4800);
FORCEPROP 3 LASTPIN (2600 4800) SIG_NAME M_G_DQS_DN<17>
J 0
(2610 4810);
DISPLAY 0.659574 (2610 4810);
PAINT MONO (2610 4810);
DISPLAY INVISIBLE (2610 4810);
FORCEPROP 1 LASTPIN (2600 4800) BN 17
J 2
(2650 4810);
DISPLAY 0.617021 (2650 4810);
PAINT PINK (2650 4810);
FORCEPROP 2 LAST CDS_LIB mstr_standard
J 2
(2650 4800);
DISPLAY 0.787234 (2650 4800);
PAINT MONO (2650 4800);
DISPLAY INVISIBLE (2650 4800);
FORCEPROP 1 LAST BODY_TYPE PLUMBING
J 2
(2650 4750);
DISPLAY 1.234043 (2650 4750);
PAINT GREEN (2650 4750);
DISPLAY INVISIBLE (2650 4750);
FORCEPROP 1 LAST HDL_TAP TRUE
J 2
(2325 4675);
DISPLAY 1.234043 (2325 4675);
PAINT GREEN (2325 4675);
DISPLAY INVISIBLE (2325 4675);
FORCEPROP 1 LAST PATH I183
J 2
(2652 4800);
DISPLAY 0.872340 (2652 4800);
PAINT GREEN (2652 4800);
DISPLAY INVISIBLE (2652 4800);
FORCEADD TAP..6
R 2
(2650 4700);
FORCEPROP 3 LASTPIN (2600 4700) SIG_NAME M_G_DQS_DN<16>
J 0
(2610 4710);
DISPLAY 0.659574 (2610 4710);
PAINT MONO (2610 4710);
DISPLAY INVISIBLE (2610 4710);
FORCEPROP 1 LASTPIN (2600 4700) BN 16
J 2
(2650 4710);
DISPLAY 0.617021 (2650 4710);
PAINT PINK (2650 4710);
FORCEPROP 2 LAST CDS_LIB mstr_standard
J 0
(2650 4700);
DISPLAY 0.787234 (2650 4700);
PAINT MONO (2650 4700);
DISPLAY INVISIBLE (2650 4700);
FORCEPROP 1 LAST BODY_TYPE PLUMBING
J 2
(2650 4650);
DISPLAY 1.234043 (2650 4650);
PAINT GREEN (2650 4650);
DISPLAY INVISIBLE (2650 4650);
FORCEPROP 1 LAST HDL_TAP TRUE
J 2
(2325 4575);
DISPLAY 1.234043 (2325 4575);
PAINT GREEN (2325 4575);
DISPLAY INVISIBLE (2325 4575);
FORCEPROP 1 LAST PATH I184
J 2
(2652 4700);
DISPLAY 0.872340 (2652 4700);
PAINT GREEN (2652 4700);
DISPLAY INVISIBLE (2652 4700);
FORCEADD OFFPAGE..3
(3350 4850);
FORCEPROP 2 LAST $XR0 57 
J 0
(3564 4850);
DISPLAY 0.638298 (3564 4850);
PAINT MONO (3564 4850);
FORCEPROP 2 LAST $XR1 77 
J 0
(3654 4850);
DISPLAY 0.638298 (3654 4850);
PAINT MONO (3654 4850);
FORCEPROP 2 LAST CDS_LIB mstr_standard
J 0
(3350 4850);
DISPLAY 0.787234 (3350 4850);
PAINT MONO (3350 4850);
DISPLAY INVISIBLE (3350 4850);
FORCEPROP 1 LAST OFFPAGE TRUE
J 0
(3675 4725);
DISPLAY 0.936170 (3675 4725);
PAINT GREEN (3675 4725);
DISPLAY INVISIBLE (3675 4725);
FORCEPROP 1 LAST COMMENT_BODY TRUE
J 0
(3300 4750);
DISPLAY 0.936170 (3300 4750);
PAINT GREEN (3300 4750);
DISPLAY INVISIBLE (3300 4750);
FORCEPROP 2 LAST PATH I185
J 0
(3575 4900);
DISPLAY 1.021277 (3575 4900);
PAINT ORANGE (3575 4900);
DISPLAY INVISIBLE (3575 4900);
FORCEADD OFFPAGE..3
(3350 4900);
FORCEPROP 2 LAST $XR0 57 
J 0
(3564 4900);
DISPLAY 0.638298 (3564 4900);
PAINT MONO (3564 4900);
FORCEPROP 2 LAST $XR1 77 
J 0
(3654 4900);
DISPLAY 0.638298 (3654 4900);
PAINT MONO (3654 4900);
FORCEPROP 2 LAST CDS_LIB mstr_standard
J 0
(3350 4900);
DISPLAY 0.787234 (3350 4900);
PAINT MONO (3350 4900);
DISPLAY INVISIBLE (3350 4900);
FORCEPROP 1 LAST OFFPAGE TRUE
J 0
(3675 4775);
DISPLAY 0.936170 (3675 4775);
PAINT GREEN (3675 4775);
DISPLAY INVISIBLE (3675 4775);
FORCEPROP 1 LAST COMMENT_BODY TRUE
J 0
(3300 4800);
DISPLAY 0.936170 (3300 4800);
PAINT GREEN (3300 4800);
DISPLAY INVISIBLE (3300 4800);
FORCEPROP 2 LAST PATH I186
J 0
(3575 4950);
DISPLAY 1.021277 (3575 4950);
PAINT ORANGE (3575 4950);
DISPLAY INVISIBLE (3575 4950);
FORCEADD P12V_NVDIMM_GHJ..1
(2150 2725);
FORCEPROP 3 LASTPIN (2150 2675) SIG_NAME P12V_NVDIMM_GHJ\g
J 0
(2160 2685);
DISPLAY 0.659574 (2160 2685);
PAINT MONO (2160 2685);
DISPLAY INVISIBLE (2160 2685);
FORCEPROP 1 LAST VOLTAGE 12.0
J 0
(2105 2682);
DISPLAY 0.340426 (2105 2682);
PAINT SKYBLUE (2105 2682);
DISPLAY INVISIBLE (2105 2682);
FORCEPROP 2 LAST CDS_LIB mstr_symbols
J 0
(2150 2725);
PAINT ORANGE (2150 2725);
DISPLAY INVISIBLE (2150 2725);
FORCEPROP 1 LAST BODY_TYPE PLUMBING
J 0
(2105 2682);
DISPLAY 0.340426 (2105 2682);
PAINT GREEN (2105 2682);
DISPLAY INVISIBLE (2105 2682);
FORCEPROP 1 LAST PATH I187
J 0
(2200 2750);
DISPLAY 0.872340 (2200 2750);
PAINT AQUA (2200 2750);
DISPLAY INVISIBLE (2200 2750);
FORCEPROP 1 LAST HDL_POWER P12V_NVDIMM_GHJ
J 1
(2150 2775);
DISPLAY 0.872340 (2150 2775);
PAINT GREEN (2150 2775);
DISPLAY INVISIBLE (2150 2775);
FORCEADD OFFPAGE..1
(-2025 2775);
FORCEPROP 2 LAST $XR0 57 
J 0
(-2246 2775);
DISPLAY 0.638298 (-2246 2775);
PAINT MONO (-2246 2775);
FORCEPROP 2 LAST $XR1 77 
J 0
(-2336 2775);
DISPLAY 0.638298 (-2336 2775);
PAINT MONO (-2336 2775);
FORCEPROP 2 LAST CDS_LIB mstr_standard
J 0
(-2025 2775);
DISPLAY 0.787234 (-2025 2775);
PAINT MONO (-2025 2775);
DISPLAY INVISIBLE (-2025 2775);
FORCEPROP 1 LAST OFFPAGE TRUE
J 0
(-1700 2650);
DISPLAY 0.936170 (-1700 2650);
PAINT GREEN (-1700 2650);
DISPLAY INVISIBLE (-1700 2650);
FORCEPROP 1 LAST COMMENT_BODY TRUE
J 0
(-1900 2675);
DISPLAY 0.936170 (-1900 2675);
PAINT GREEN (-1900 2675);
DISPLAY INVISIBLE (-1900 2675);
FORCEPROP 2 LAST PATH I19
J 0
(-2225 2825);
DISPLAY 1.021277 (-2225 2825);
PAINT ORANGE (-2225 2825);
DISPLAY INVISIBLE (-2225 2825);
FORCEADD CAP_A..1
R 2
(-2675 875);
FORCEPROP 1 LAST LOCATION C9T7
J 2
(-2725 975);
DISPLAY 0.617021 (-2725 975);
PAINT AQUA (-2725 975);
FORCEPROP 1 LAST PART_NUMBER A36096-045
J 2
(-2725 725);
DISPLAY 0.617021 (-2725 725);
PAINT BLUE (-2725 725);
FORCEPROP 1 LAST VALUE 0.01UF
J 2
(-2725 925);
DISPLAY 0.617021 (-2725 925);
PAINT SKYBLUE (-2725 925);
FORCEPROP 1 LAST TOLERANCE 10%
J 2
(-2725 825);
DISPLAY 0.617021 (-2725 825);
PAINT SKYBLUE (-2725 825);
FORCEPROP 1 LAST PACK_TYPE 0402V
J 2
(-2725 675);
DISPLAY 0.617021 (-2725 675);
PAINT SKYBLUE (-2725 675);
FORCEPROP 1 LAST VOLTAGE 25V
J 2
(-2725 875);
DISPLAY 0.617021 (-2725 875);
PAINT SKYBLUE (-2725 875);
FORCEPROP 1 LAST MATERIAL X7R
J 2
(-2725 775);
DISPLAY 0.617021 (-2725 775);
PAINT SKYBLUE (-2725 775);
FORCEPROP 2 LAST CDS_LOCATION C9T7
J 2
(-2725 975);
DISPLAY 0.617021 (-2725 975);
PAINT AQUA (-2725 975);
DISPLAY INVISIBLE (-2725 975);
FORCEPROP 2 LAST BOM_COST MEM
J 0
(-2675 875);
PAINT ORANGE (-2675 875);
DISPLAY INVISIBLE (-2675 875);
FORCEPROP 2 LAST CDS_LIB dev_discrete
J 0
(-2675 875);
PAINT ORANGE (-2675 875);
DISPLAY INVISIBLE (-2675 875);
FORCEPROP 2 LAST CDS_SEC 1
J 0
(-2725 1075);
PAINT MONO (-2725 1075);
DISPLAY INVISIBLE (-2725 1075);
FORCEPROP 2 LAST $SEC 1
J 0
(-2725 1075);
PAINT MONO (-2725 1075);
DISPLAY INVISIBLE (-2725 1075);
FORCEPROP 1 LAST PATH I2
J 2
(-2725 1025);
DISPLAY 0.978723 (-2725 1025);
PAINT WHITE (-2725 1025);
DISPLAY INVISIBLE (-2725 1025);
FORCEPROP 2 LAST ROOM DDR4_GH_G
J 0
(-2675 875);
PAINT ORANGE (-2675 875);
DISPLAY INVISIBLE (-2675 875);
FORCEPROP 1 LASTPIN (-2675 975) $PN 1
J 2
(-2685 955);
DISPLAY 0.787234 (-2685 955);
PAINT ORANGE (-2685 955);
DISPLAY INVISIBLE (-2685 955);
FORCEPROP 1 LASTPIN (-2675 775) $PN 2
J 2
(-2685 755);
DISPLAY 0.787234 (-2685 755);
PAINT ORANGE (-2685 755);
DISPLAY INVISIBLE (-2685 755);
FORCEADD OFFPAGE..1
(-2025 2825);
FORCEPROP 2 LAST $XR0 57 
J 0
(-2246 2825);
DISPLAY 0.638298 (-2246 2825);
PAINT MONO (-2246 2825);
FORCEPROP 2 LAST $XR1 77 
J 0
(-2336 2825);
DISPLAY 0.638298 (-2336 2825);
PAINT MONO (-2336 2825);
FORCEPROP 2 LAST CDS_LIB mstr_standard
J 0
(-2025 2825);
DISPLAY 0.787234 (-2025 2825);
PAINT MONO (-2025 2825);
DISPLAY INVISIBLE (-2025 2825);
FORCEPROP 1 LAST OFFPAGE TRUE
J 0
(-1700 2700);
DISPLAY 0.936170 (-1700 2700);
PAINT GREEN (-1700 2700);
DISPLAY INVISIBLE (-1700 2700);
FORCEPROP 1 LAST COMMENT_BODY TRUE
J 0
(-1900 2725);
DISPLAY 0.936170 (-1900 2725);
PAINT GREEN (-1900 2725);
DISPLAY INVISIBLE (-1900 2725);
FORCEPROP 2 LAST PATH I20
J 0
(-2225 2875);
DISPLAY 1.021277 (-2225 2875);
PAINT ORANGE (-2225 2875);
DISPLAY INVISIBLE (-2225 2875);
FORCEADD TAP..6
(-1375 1875);
FORCEPROP 3 LASTPIN (-1325 1875) SIG_NAME M_G_ECC<1>
J 0
(-1315 1885);
DISPLAY 0.659574 (-1315 1885);
PAINT MONO (-1315 1885);
DISPLAY INVISIBLE (-1315 1885);
FORCEPROP 1 LASTPIN (-1325 1875) BN 1
J 0
(-1375 1885);
DISPLAY 0.617021 (-1375 1885);
PAINT PINK (-1375 1885);
FORCEPROP 2 LAST CDS_LIB mstr_standard
J 0
(-1375 1875);
DISPLAY 0.787234 (-1375 1875);
PAINT MONO (-1375 1875);
DISPLAY INVISIBLE (-1375 1875);
FORCEPROP 1 LAST BODY_TYPE PLUMBING
J 0
(-1375 1825);
DISPLAY 1.234043 (-1375 1825);
PAINT GREEN (-1375 1825);
DISPLAY INVISIBLE (-1375 1825);
FORCEPROP 1 LAST HDL_TAP TRUE
J 0
(-1050 1750);
DISPLAY 1.234043 (-1050 1750);
PAINT GREEN (-1050 1750);
DISPLAY INVISIBLE (-1050 1750);
FORCEPROP 1 LAST PATH I21
J 0
(-1377 1875);
DISPLAY 0.872340 (-1377 1875);
PAINT GREEN (-1377 1875);
DISPLAY INVISIBLE (-1377 1875);
FORCEADD TAP..6
(-1375 1925);
FORCEPROP 3 LASTPIN (-1325 1925) SIG_NAME M_G_ECC<2>
J 0
(-1315 1935);
DISPLAY 0.659574 (-1315 1935);
PAINT MONO (-1315 1935);
DISPLAY INVISIBLE (-1315 1935);
FORCEPROP 1 LASTPIN (-1325 1925) BN 2
J 0
(-1375 1935);
DISPLAY 0.617021 (-1375 1935);
PAINT PINK (-1375 1935);
FORCEPROP 2 LAST CDS_LIB mstr_standard
J 0
(-1375 1925);
DISPLAY 0.787234 (-1375 1925);
PAINT MONO (-1375 1925);
DISPLAY INVISIBLE (-1375 1925);
FORCEPROP 1 LAST BODY_TYPE PLUMBING
J 0
(-1375 1875);
DISPLAY 1.234043 (-1375 1875);
PAINT GREEN (-1375 1875);
DISPLAY INVISIBLE (-1375 1875);
FORCEPROP 1 LAST HDL_TAP TRUE
J 0
(-1050 1800);
DISPLAY 1.234043 (-1050 1800);
PAINT GREEN (-1050 1800);
DISPLAY INVISIBLE (-1050 1800);
FORCEPROP 1 LAST PATH I22
J 0
(-1377 1925);
DISPLAY 0.872340 (-1377 1925);
PAINT GREEN (-1377 1925);
DISPLAY INVISIBLE (-1377 1925);
FORCEADD TAP..6
(-1375 1975);
FORCEPROP 3 LASTPIN (-1325 1975) SIG_NAME M_G_ECC<3>
J 0
(-1315 1985);
DISPLAY 0.659574 (-1315 1985);
PAINT MONO (-1315 1985);
DISPLAY INVISIBLE (-1315 1985);
FORCEPROP 1 LASTPIN (-1325 1975) BN 3
J 0
(-1375 1985);
DISPLAY 0.617021 (-1375 1985);
PAINT PINK (-1375 1985);
FORCEPROP 2 LAST CDS_LIB mstr_standard
J 0
(-1375 1975);
DISPLAY 0.787234 (-1375 1975);
PAINT MONO (-1375 1975);
DISPLAY INVISIBLE (-1375 1975);
FORCEPROP 1 LAST BODY_TYPE PLUMBING
J 0
(-1375 1925);
DISPLAY 1.234043 (-1375 1925);
PAINT GREEN (-1375 1925);
DISPLAY INVISIBLE (-1375 1925);
FORCEPROP 1 LAST HDL_TAP TRUE
J 0
(-1050 1850);
DISPLAY 1.234043 (-1050 1850);
PAINT GREEN (-1050 1850);
DISPLAY INVISIBLE (-1050 1850);
FORCEPROP 1 LAST PATH I23
J 0
(-1377 1975);
DISPLAY 0.872340 (-1377 1975);
PAINT GREEN (-1377 1975);
DISPLAY INVISIBLE (-1377 1975);
FORCEADD TAP..6
(-1375 2075);
FORCEPROP 3 LASTPIN (-1325 2075) SIG_NAME M_G_ECC<5>
J 0
(-1315 2085);
DISPLAY 0.659574 (-1315 2085);
PAINT MONO (-1315 2085);
DISPLAY INVISIBLE (-1315 2085);
FORCEPROP 1 LASTPIN (-1325 2075) BN 5
J 0
(-1375 2085);
DISPLAY 0.617021 (-1375 2085);
PAINT PINK (-1375 2085);
FORCEPROP 2 LAST CDS_LIB mstr_standard
J 0
(-1375 2075);
DISPLAY 0.787234 (-1375 2075);
PAINT MONO (-1375 2075);
DISPLAY INVISIBLE (-1375 2075);
FORCEPROP 1 LAST BODY_TYPE PLUMBING
J 0
(-1375 2025);
DISPLAY 1.234043 (-1375 2025);
PAINT GREEN (-1375 2025);
DISPLAY INVISIBLE (-1375 2025);
FORCEPROP 1 LAST HDL_TAP TRUE
J 0
(-1050 1950);
DISPLAY 1.234043 (-1050 1950);
PAINT GREEN (-1050 1950);
DISPLAY INVISIBLE (-1050 1950);
FORCEPROP 1 LAST PATH I24
J 0
(-1377 2075);
DISPLAY 0.872340 (-1377 2075);
PAINT GREEN (-1377 2075);
DISPLAY INVISIBLE (-1377 2075);
FORCEADD TAP..6
(-1375 2025);
FORCEPROP 3 LASTPIN (-1325 2025) SIG_NAME M_G_ECC<4>
J 0
(-1315 2035);
DISPLAY 0.659574 (-1315 2035);
PAINT MONO (-1315 2035);
DISPLAY INVISIBLE (-1315 2035);
FORCEPROP 1 LASTPIN (-1325 2025) BN 4
J 0
(-1375 2035);
DISPLAY 0.617021 (-1375 2035);
PAINT PINK (-1375 2035);
FORCEPROP 2 LAST CDS_LIB mstr_standard
J 0
(-1375 2025);
DISPLAY 0.787234 (-1375 2025);
PAINT MONO (-1375 2025);
DISPLAY INVISIBLE (-1375 2025);
FORCEPROP 1 LAST BODY_TYPE PLUMBING
J 0
(-1375 1975);
DISPLAY 1.234043 (-1375 1975);
PAINT GREEN (-1375 1975);
DISPLAY INVISIBLE (-1375 1975);
FORCEPROP 1 LAST HDL_TAP TRUE
J 0
(-1050 1900);
DISPLAY 1.234043 (-1050 1900);
PAINT GREEN (-1050 1900);
DISPLAY INVISIBLE (-1050 1900);
FORCEPROP 1 LAST PATH I25
J 0
(-1377 2025);
DISPLAY 0.872340 (-1377 2025);
PAINT GREEN (-1377 2025);
DISPLAY INVISIBLE (-1377 2025);
FORCEADD TAP..6
(-1375 2175);
FORCEPROP 3 LASTPIN (-1325 2175) SIG_NAME M_G_ECC<7>
J 0
(-1315 2185);
DISPLAY 0.659574 (-1315 2185);
PAINT MONO (-1315 2185);
DISPLAY INVISIBLE (-1315 2185);
FORCEPROP 1 LASTPIN (-1325 2175) BN 7
J 0
(-1375 2185);
DISPLAY 0.617021 (-1375 2185);
PAINT PINK (-1375 2185);
FORCEPROP 2 LAST CDS_LIB mstr_standard
J 0
(-1375 2175);
DISPLAY 0.787234 (-1375 2175);
PAINT MONO (-1375 2175);
DISPLAY INVISIBLE (-1375 2175);
FORCEPROP 1 LAST BODY_TYPE PLUMBING
J 0
(-1375 2125);
DISPLAY 1.234043 (-1375 2125);
PAINT GREEN (-1375 2125);
DISPLAY INVISIBLE (-1375 2125);
FORCEPROP 1 LAST HDL_TAP TRUE
J 0
(-1050 2050);
DISPLAY 1.234043 (-1050 2050);
PAINT GREEN (-1050 2050);
DISPLAY INVISIBLE (-1050 2050);
FORCEPROP 1 LAST PATH I26
J 0
(-1377 2175);
DISPLAY 0.872340 (-1377 2175);
PAINT GREEN (-1377 2175);
DISPLAY INVISIBLE (-1377 2175);
FORCEADD TAP..6
(-1375 2125);
FORCEPROP 3 LASTPIN (-1325 2125) SIG_NAME M_G_ECC<6>
J 0
(-1315 2135);
DISPLAY 0.659574 (-1315 2135);
PAINT MONO (-1315 2135);
DISPLAY INVISIBLE (-1315 2135);
FORCEPROP 1 LASTPIN (-1325 2125) BN 6
J 0
(-1375 2135);
DISPLAY 0.617021 (-1375 2135);
PAINT PINK (-1375 2135);
FORCEPROP 2 LAST CDS_LIB mstr_standard
J 0
(-1375 2125);
DISPLAY 0.787234 (-1375 2125);
PAINT MONO (-1375 2125);
DISPLAY INVISIBLE (-1375 2125);
FORCEPROP 1 LAST BODY_TYPE PLUMBING
J 0
(-1375 2075);
DISPLAY 1.234043 (-1375 2075);
PAINT GREEN (-1375 2075);
DISPLAY INVISIBLE (-1375 2075);
FORCEPROP 1 LAST HDL_TAP TRUE
J 0
(-1050 2000);
DISPLAY 1.234043 (-1050 2000);
PAINT GREEN (-1050 2000);
DISPLAY INVISIBLE (-1050 2000);
FORCEPROP 1 LAST PATH I27
J 0
(-1377 2125);
DISPLAY 0.872340 (-1377 2125);
PAINT GREEN (-1377 2125);
DISPLAY INVISIBLE (-1377 2125);
FORCEADD TAP..6
(-1375 2325);
FORCEPROP 3 LASTPIN (-1325 2325) SIG_NAME M_G_ODT<3>
J 0
(-1315 2335);
DISPLAY 0.659574 (-1315 2335);
PAINT MONO (-1315 2335);
DISPLAY INVISIBLE (-1315 2335);
FORCEPROP 1 LASTPIN (-1325 2325) BN 3
J 0
(-1375 2335);
DISPLAY 0.617021 (-1375 2335);
PAINT PINK (-1375 2335);
FORCEPROP 2 LAST CDS_LIB mstr_standard
J 0
(-1375 2325);
DISPLAY 0.787234 (-1375 2325);
PAINT MONO (-1375 2325);
DISPLAY INVISIBLE (-1375 2325);
FORCEPROP 1 LAST BODY_TYPE PLUMBING
J 0
(-1375 2275);
DISPLAY 1.234043 (-1375 2275);
PAINT GREEN (-1375 2275);
DISPLAY INVISIBLE (-1375 2275);
FORCEPROP 1 LAST HDL_TAP TRUE
J 0
(-1050 2200);
DISPLAY 1.234043 (-1050 2200);
PAINT GREEN (-1050 2200);
DISPLAY INVISIBLE (-1050 2200);
FORCEPROP 1 LAST PATH I28
J 0
(-1377 2325);
DISPLAY 0.872340 (-1377 2325);
PAINT GREEN (-1377 2325);
DISPLAY INVISIBLE (-1377 2325);
FORCEADD TAP..6
(-1375 2275);
FORCEPROP 3 LASTPIN (-1325 2275) SIG_NAME M_G_ODT<2>
J 0
(-1315 2285);
DISPLAY 0.659574 (-1315 2285);
PAINT MONO (-1315 2285);
DISPLAY INVISIBLE (-1315 2285);
FORCEPROP 1 LASTPIN (-1325 2275) BN 2
J 0
(-1375 2285);
DISPLAY 0.617021 (-1375 2285);
PAINT PINK (-1375 2285);
FORCEPROP 2 LAST CDS_LIB mstr_standard
J 0
(-1375 2275);
DISPLAY 0.787234 (-1375 2275);
PAINT MONO (-1375 2275);
DISPLAY INVISIBLE (-1375 2275);
FORCEPROP 1 LAST BODY_TYPE PLUMBING
J 0
(-1375 2225);
DISPLAY 1.234043 (-1375 2225);
PAINT GREEN (-1375 2225);
DISPLAY INVISIBLE (-1375 2225);
FORCEPROP 1 LAST HDL_TAP TRUE
J 0
(-1050 2150);
DISPLAY 1.234043 (-1050 2150);
PAINT GREEN (-1050 2150);
DISPLAY INVISIBLE (-1050 2150);
FORCEPROP 1 LAST PATH I29
J 0
(-1377 2275);
DISPLAY 0.872340 (-1377 2275);
PAINT GREEN (-1377 2275);
DISPLAY INVISIBLE (-1377 2275);
FORCEADD GND..1
R 2
(-3325 1225);
FORCEPROP 3 LASTPIN (-3325 1275) SIG_NAME GND\g
J 0
(-3315 1285);
DISPLAY 0.659574 (-3315 1285);
PAINT MONO (-3315 1285);
DISPLAY INVISIBLE (-3315 1285);
FORCEPROP 1 LAST VOLTAGE 0.0V
J 2
(-3280 1182);
DISPLAY 0.340426 (-3280 1182);
PAINT SKYBLUE (-3280 1182);
DISPLAY INVISIBLE (-3280 1182);
FORCEPROP 1 LAST SIZE 1B
J 2
(-3400 1175);
DISPLAY 1.170213 (-3400 1175);
PAINT GREEN (-3400 1175);
DISPLAY INVISIBLE (-3400 1175);
FORCEPROP 2 LAST CDS_LIB mstr_symbols
J 0
(-3325 1225);
DISPLAY 0.787234 (-3325 1225);
PAINT MONO (-3325 1225);
DISPLAY INVISIBLE (-3325 1225);
FORCEPROP 2 LAST BOM_COST MEM
J 0
(-3325 1230);
PAINT ORANGE (-3325 1230);
DISPLAY INVISIBLE (-3325 1230);
FORCEPROP 1 LAST BODY_TYPE PLUMBING
J 2
(-3280 1182);
DISPLAY 0.340426 (-3280 1182);
PAINT GREEN (-3280 1182);
DISPLAY INVISIBLE (-3280 1182);
FORCEPROP 1 LAST PATH I3
J 2
(-3400 1225);
DISPLAY 0.872340 (-3400 1225);
PAINT AQUA (-3400 1225);
DISPLAY INVISIBLE (-3400 1225);
FORCEPROP 2 LAST ROOM DDR4_GH_G
J 0
(-3325 1230);
PAINT ORANGE (-3325 1230);
DISPLAY INVISIBLE (-3325 1230);
FORCEPROP 1 LAST HDL_POWER GND
J 2
(-3325 1375);
DISPLAY 0.553191 (-3325 1375);
PAINT GREEN (-3325 1375);
DISPLAY INVISIBLE (-3325 1375);
FORCEADD TAP..6
(-1375 2425);
FORCEPROP 3 LASTPIN (-1325 2425) SIG_NAME M_G_CKE<2>
J 0
(-1315 2435);
DISPLAY 0.659574 (-1315 2435);
PAINT MONO (-1315 2435);
DISPLAY INVISIBLE (-1315 2435);
FORCEPROP 1 LASTPIN (-1325 2425) BN 2
J 0
(-1375 2435);
DISPLAY 0.617021 (-1375 2435);
PAINT PINK (-1375 2435);
FORCEPROP 2 LAST CDS_LIB mstr_standard
J 0
(-1375 2425);
DISPLAY 0.787234 (-1375 2425);
PAINT MONO (-1375 2425);
DISPLAY INVISIBLE (-1375 2425);
FORCEPROP 1 LAST BODY_TYPE PLUMBING
J 0
(-1375 2375);
DISPLAY 1.234043 (-1375 2375);
PAINT GREEN (-1375 2375);
DISPLAY INVISIBLE (-1375 2375);
FORCEPROP 1 LAST HDL_TAP TRUE
J 0
(-1050 2300);
DISPLAY 1.234043 (-1050 2300);
PAINT GREEN (-1050 2300);
DISPLAY INVISIBLE (-1050 2300);
FORCEPROP 1 LAST PATH I30
J 0
(-1377 2425);
DISPLAY 0.872340 (-1377 2425);
PAINT GREEN (-1377 2425);
DISPLAY INVISIBLE (-1377 2425);
FORCEADD TAP..6
(-1375 2475);
FORCEPROP 3 LASTPIN (-1325 2475) SIG_NAME M_G_CKE<3>
J 0
(-1315 2485);
DISPLAY 0.659574 (-1315 2485);
PAINT MONO (-1315 2485);
DISPLAY INVISIBLE (-1315 2485);
FORCEPROP 1 LASTPIN (-1325 2475) BN 3
J 0
(-1375 2485);
DISPLAY 0.617021 (-1375 2485);
PAINT PINK (-1375 2485);
FORCEPROP 2 LAST CDS_LIB mstr_standard
J 0
(-1375 2475);
DISPLAY 0.787234 (-1375 2475);
PAINT MONO (-1375 2475);
DISPLAY INVISIBLE (-1375 2475);
FORCEPROP 1 LAST BODY_TYPE PLUMBING
J 0
(-1375 2425);
DISPLAY 1.234043 (-1375 2425);
PAINT GREEN (-1375 2425);
DISPLAY INVISIBLE (-1375 2425);
FORCEPROP 1 LAST HDL_TAP TRUE
J 0
(-1050 2350);
DISPLAY 1.234043 (-1050 2350);
PAINT GREEN (-1050 2350);
DISPLAY INVISIBLE (-1050 2350);
FORCEPROP 1 LAST PATH I31
J 0
(-1377 2475);
DISPLAY 0.872340 (-1377 2475);
PAINT GREEN (-1377 2475);
DISPLAY INVISIBLE (-1377 2475);
FORCEADD TAP..6
(-1375 2575);
FORCEPROP 3 LASTPIN (-1325 2575) SIG_NAME M_G_CS_N<4>
J 0
(-1315 2585);
DISPLAY 0.659574 (-1315 2585);
PAINT MONO (-1315 2585);
DISPLAY INVISIBLE (-1315 2585);
FORCEPROP 1 LASTPIN (-1325 2575) BN 4
J 0
(-1375 2585);
DISPLAY 0.617021 (-1375 2585);
PAINT PINK (-1375 2585);
FORCEPROP 2 LAST CDS_LIB mstr_standard
J 0
(-1375 2575);
DISPLAY 0.787234 (-1375 2575);
PAINT MONO (-1375 2575);
DISPLAY INVISIBLE (-1375 2575);
FORCEPROP 1 LAST BODY_TYPE PLUMBING
J 0
(-1375 2525);
DISPLAY 1.234043 (-1375 2525);
PAINT GREEN (-1375 2525);
DISPLAY INVISIBLE (-1375 2525);
FORCEPROP 1 LAST HDL_TAP TRUE
J 0
(-1050 2450);
DISPLAY 1.234043 (-1050 2450);
PAINT GREEN (-1050 2450);
DISPLAY INVISIBLE (-1050 2450);
FORCEPROP 1 LAST PATH I32
J 0
(-1377 2575);
DISPLAY 0.872340 (-1377 2575);
PAINT GREEN (-1377 2575);
DISPLAY INVISIBLE (-1377 2575);
FORCEADD TAP..6
(-1375 2675);
FORCEPROP 3 LASTPIN (-1325 2675) SIG_NAME M_G_CS_N<6>
J 0
(-1315 2685);
DISPLAY 0.659574 (-1315 2685);
PAINT MONO (-1315 2685);
DISPLAY INVISIBLE (-1315 2685);
FORCEPROP 1 LASTPIN (-1325 2675) BN 6
J 0
(-1375 2685);
DISPLAY 0.617021 (-1375 2685);
PAINT PINK (-1375 2685);
FORCEPROP 2 LAST CDS_LIB mstr_standard
J 0
(-1375 2675);
DISPLAY 0.787234 (-1375 2675);
PAINT MONO (-1375 2675);
DISPLAY INVISIBLE (-1375 2675);
FORCEPROP 1 LAST BODY_TYPE PLUMBING
J 0
(-1375 2625);
DISPLAY 1.234043 (-1375 2625);
PAINT GREEN (-1375 2625);
DISPLAY INVISIBLE (-1375 2625);
FORCEPROP 1 LAST HDL_TAP TRUE
J 0
(-1050 2550);
DISPLAY 1.234043 (-1050 2550);
PAINT GREEN (-1050 2550);
DISPLAY INVISIBLE (-1050 2550);
FORCEPROP 1 LAST PATH I33
J 0
(-1377 2675);
DISPLAY 0.872340 (-1377 2675);
PAINT GREEN (-1377 2675);
DISPLAY INVISIBLE (-1377 2675);
FORCEADD TAP..6
(-1375 2625);
FORCEPROP 3 LASTPIN (-1325 2625) SIG_NAME M_G_CS_N<5>
J 0
(-1315 2635);
DISPLAY 0.659574 (-1315 2635);
PAINT MONO (-1315 2635);
DISPLAY INVISIBLE (-1315 2635);
FORCEPROP 1 LASTPIN (-1325 2625) BN 5
J 0
(-1375 2635);
DISPLAY 0.617021 (-1375 2635);
PAINT PINK (-1375 2635);
FORCEPROP 2 LAST CDS_LIB mstr_standard
J 0
(-1375 2625);
DISPLAY 0.787234 (-1375 2625);
PAINT MONO (-1375 2625);
DISPLAY INVISIBLE (-1375 2625);
FORCEPROP 1 LAST BODY_TYPE PLUMBING
J 0
(-1375 2575);
DISPLAY 1.234043 (-1375 2575);
PAINT GREEN (-1375 2575);
DISPLAY INVISIBLE (-1375 2575);
FORCEPROP 1 LAST HDL_TAP TRUE
J 0
(-1050 2500);
DISPLAY 1.234043 (-1050 2500);
PAINT GREEN (-1050 2500);
DISPLAY INVISIBLE (-1050 2500);
FORCEPROP 1 LAST PATH I34
J 0
(-1377 2625);
DISPLAY 0.872340 (-1377 2625);
PAINT GREEN (-1377 2625);
DISPLAY INVISIBLE (-1377 2625);
FORCEADD TAP..6
(-1375 2725);
FORCEPROP 3 LASTPIN (-1325 2725) SIG_NAME M_G_CS_N<7>
J 0
(-1315 2735);
DISPLAY 0.659574 (-1315 2735);
PAINT MONO (-1315 2735);
DISPLAY INVISIBLE (-1315 2735);
FORCEPROP 1 LASTPIN (-1325 2725) BN 7
J 0
(-1375 2735);
DISPLAY 0.617021 (-1375 2735);
PAINT PINK (-1375 2735);
FORCEPROP 2 LAST CDS_LIB mstr_standard
J 0
(-1375 2725);
DISPLAY 0.787234 (-1375 2725);
PAINT MONO (-1375 2725);
DISPLAY INVISIBLE (-1375 2725);
FORCEPROP 1 LAST BODY_TYPE PLUMBING
J 0
(-1375 2675);
DISPLAY 1.234043 (-1375 2675);
PAINT GREEN (-1375 2675);
DISPLAY INVISIBLE (-1375 2675);
FORCEPROP 1 LAST HDL_TAP TRUE
J 0
(-1050 2600);
DISPLAY 1.234043 (-1050 2600);
PAINT GREEN (-1050 2600);
DISPLAY INVISIBLE (-1050 2600);
FORCEPROP 1 LAST PATH I35
J 0
(-1377 2725);
DISPLAY 0.872340 (-1377 2725);
PAINT GREEN (-1377 2725);
DISPLAY INVISIBLE (-1377 2725);
FORCEADD OFFPAGE..1
(-2025 3050);
FORCEPROP 2 LAST $XR0 57 
J 0
(-2246 3050);
DISPLAY 0.638298 (-2246 3050);
PAINT MONO (-2246 3050);
FORCEPROP 2 LAST $XR1 77 
J 0
(-2336 3050);
DISPLAY 0.638298 (-2336 3050);
PAINT MONO (-2336 3050);
FORCEPROP 2 LAST CDS_LIB mstr_standard
J 0
(-2025 3050);
DISPLAY 0.787234 (-2025 3050);
PAINT MONO (-2025 3050);
DISPLAY INVISIBLE (-2025 3050);
FORCEPROP 1 LAST OFFPAGE TRUE
J 0
(-1700 2925);
DISPLAY 0.936170 (-1700 2925);
PAINT GREEN (-1700 2925);
DISPLAY INVISIBLE (-1700 2925);
FORCEPROP 1 LAST COMMENT_BODY TRUE
J 0
(-1900 2950);
DISPLAY 0.936170 (-1900 2950);
PAINT GREEN (-1900 2950);
DISPLAY INVISIBLE (-1900 2950);
FORCEPROP 2 LAST PATH I36
J 0
(-2225 3100);
DISPLAY 1.021277 (-2225 3100);
PAINT ORANGE (-2225 3100);
DISPLAY INVISIBLE (-2225 3100);
FORCEADD OFFPAGE..1
(-2025 3100);
FORCEPROP 2 LAST $XR0 57 
J 0
(-2246 3100);
DISPLAY 0.638298 (-2246 3100);
PAINT MONO (-2246 3100);
FORCEPROP 2 LAST $XR1 77 
J 0
(-2336 3100);
DISPLAY 0.638298 (-2336 3100);
PAINT MONO (-2336 3100);
FORCEPROP 2 LAST CDS_LIB mstr_standard
J 0
(-2025 3100);
DISPLAY 0.787234 (-2025 3100);
PAINT MONO (-2025 3100);
DISPLAY INVISIBLE (-2025 3100);
FORCEPROP 1 LAST OFFPAGE TRUE
J 0
(-1700 2975);
DISPLAY 0.936170 (-1700 2975);
PAINT GREEN (-1700 2975);
DISPLAY INVISIBLE (-1700 2975);
FORCEPROP 1 LAST COMMENT_BODY TRUE
J 0
(-1900 3000);
DISPLAY 0.936170 (-1900 3000);
PAINT GREEN (-1900 3000);
DISPLAY INVISIBLE (-1900 3000);
FORCEPROP 2 LAST PATH I37
J 0
(-2225 3150);
DISPLAY 1.021277 (-2225 3150);
PAINT ORANGE (-2225 3150);
DISPLAY INVISIBLE (-2225 3150);
FORCEADD OFFPAGE..1
(-2025 3225);
FORCEPROP 2 LAST $XR0 57 
J 0
(-2246 3225);
DISPLAY 0.638298 (-2246 3225);
PAINT MONO (-2246 3225);
FORCEPROP 2 LAST $XR1 77 
J 0
(-2336 3225);
DISPLAY 0.638298 (-2336 3225);
PAINT MONO (-2336 3225);
FORCEPROP 2 LAST CDS_LIB mstr_standard
J 0
(-2025 3225);
DISPLAY 0.787234 (-2025 3225);
PAINT MONO (-2025 3225);
DISPLAY INVISIBLE (-2025 3225);
FORCEPROP 1 LAST OFFPAGE TRUE
J 0
(-1700 3100);
DISPLAY 0.936170 (-1700 3100);
PAINT GREEN (-1700 3100);
DISPLAY INVISIBLE (-1700 3100);
FORCEPROP 1 LAST COMMENT_BODY TRUE
J 0
(-1900 3125);
DISPLAY 0.936170 (-1900 3125);
PAINT GREEN (-1900 3125);
DISPLAY INVISIBLE (-1900 3125);
FORCEPROP 2 LAST PATH I38
J 0
(-2225 3275);
DISPLAY 1.021277 (-2225 3275);
PAINT ORANGE (-2225 3275);
DISPLAY INVISIBLE (-2225 3275);
FORCEADD OFFPAGE..1
(-2025 3350);
FORCEPROP 2 LAST $XR0 57 
J 0
(-2246 3350);
DISPLAY 0.638298 (-2246 3350);
PAINT MONO (-2246 3350);
FORCEPROP 2 LAST $XR1 77 
J 0
(-2336 3350);
DISPLAY 0.638298 (-2336 3350);
PAINT MONO (-2336 3350);
FORCEPROP 2 LAST CDS_LIB mstr_standard
J 0
(-2025 3350);
DISPLAY 0.787234 (-2025 3350);
PAINT MONO (-2025 3350);
DISPLAY INVISIBLE (-2025 3350);
FORCEPROP 1 LAST OFFPAGE TRUE
J 0
(-1700 3225);
DISPLAY 0.936170 (-1700 3225);
PAINT GREEN (-1700 3225);
DISPLAY INVISIBLE (-1700 3225);
FORCEPROP 1 LAST COMMENT_BODY TRUE
J 0
(-1900 3250);
DISPLAY 0.936170 (-1900 3250);
PAINT GREEN (-1900 3250);
DISPLAY INVISIBLE (-1900 3250);
FORCEPROP 2 LAST PATH I39
J 0
(-2225 3400);
DISPLAY 1.021277 (-2225 3400);
PAINT ORANGE (-2225 3400);
DISPLAY INVISIBLE (-2225 3400);
FORCEADD OFFPAGE..1
(-2825 1075);
FORCEPROP 2 LAST $XR0 100 
J 0
(-3077 1075);
DISPLAY 0.638298 (-3077 1075);
PAINT MONO (-3077 1075);
FORCEPROP 2 LAST $XR1 77 
J 0
(-3167 1075);
DISPLAY 0.638298 (-3167 1075);
PAINT MONO (-3167 1075);
FORCEPROP 2 LAST CDS_LIB mstr_standard
J 0
(-2825 1075);
DISPLAY 0.787234 (-2825 1075);
PAINT MONO (-2825 1075);
DISPLAY INVISIBLE (-2825 1075);
FORCEPROP 1 LAST OFFPAGE TRUE
J 0
(-2500 950);
DISPLAY 0.936170 (-2500 950);
PAINT GREEN (-2500 950);
DISPLAY INVISIBLE (-2500 950);
FORCEPROP 1 LAST COMMENT_BODY TRUE
J 0
(-2700 975);
DISPLAY 0.936170 (-2700 975);
PAINT GREEN (-2700 975);
DISPLAY INVISIBLE (-2700 975);
FORCEPROP 2 LAST PATH I4
J 0
(-3025 1125);
DISPLAY 1.021277 (-3025 1125);
PAINT ORANGE (-3025 1125);
DISPLAY INVISIBLE (-3025 1125);
FORCEADD TAP..6
(-1575 2975);
FORCEPROP 3 LASTPIN (-1525 2975) SIG_NAME M_G_CLK_DN<3>
J 0
(-1515 2985);
DISPLAY 0.659574 (-1515 2985);
PAINT MONO (-1515 2985);
DISPLAY INVISIBLE (-1515 2985);
FORCEPROP 1 LASTPIN (-1525 2975) BN 3
J 0
(-1575 2985);
DISPLAY 0.617021 (-1575 2985);
PAINT PINK (-1575 2985);
FORCEPROP 2 LAST CDS_LIB mstr_standard
J 0
(-1575 2975);
DISPLAY 0.787234 (-1575 2975);
PAINT MONO (-1575 2975);
DISPLAY INVISIBLE (-1575 2975);
FORCEPROP 1 LAST BODY_TYPE PLUMBING
J 0
(-1575 2925);
DISPLAY 1.234043 (-1575 2925);
PAINT GREEN (-1575 2925);
DISPLAY INVISIBLE (-1575 2925);
FORCEPROP 1 LAST HDL_TAP TRUE
J 0
(-1250 2850);
DISPLAY 1.234043 (-1250 2850);
PAINT GREEN (-1250 2850);
DISPLAY INVISIBLE (-1250 2850);
FORCEPROP 1 LAST PATH I40
J 0
(-1577 2975);
DISPLAY 0.872340 (-1577 2975);
PAINT GREEN (-1577 2975);
DISPLAY INVISIBLE (-1577 2975);
FORCEADD TAP..6
(-1575 2875);
FORCEPROP 3 LASTPIN (-1525 2875) SIG_NAME M_G_CLK_DN<2>
J 0
(-1515 2885);
DISPLAY 0.659574 (-1515 2885);
PAINT MONO (-1515 2885);
DISPLAY INVISIBLE (-1515 2885);
FORCEPROP 1 LASTPIN (-1525 2875) BN 2
J 0
(-1575 2885);
DISPLAY 0.617021 (-1575 2885);
PAINT PINK (-1575 2885);
FORCEPROP 2 LAST CDS_LIB mstr_standard
J 0
(-1575 2875);
DISPLAY 0.787234 (-1575 2875);
PAINT MONO (-1575 2875);
DISPLAY INVISIBLE (-1575 2875);
FORCEPROP 1 LAST BODY_TYPE PLUMBING
J 0
(-1575 2825);
DISPLAY 1.234043 (-1575 2825);
PAINT GREEN (-1575 2825);
DISPLAY INVISIBLE (-1575 2825);
FORCEPROP 1 LAST HDL_TAP TRUE
J 0
(-1250 2750);
DISPLAY 1.234043 (-1250 2750);
PAINT GREEN (-1250 2750);
DISPLAY INVISIBLE (-1250 2750);
FORCEPROP 1 LAST PATH I41
J 0
(-1577 2875);
DISPLAY 0.872340 (-1577 2875);
PAINT GREEN (-1577 2875);
DISPLAY INVISIBLE (-1577 2875);
FORCEADD TAP..6
(-1375 2925);
FORCEPROP 3 LASTPIN (-1325 2925) SIG_NAME M_G_CLK_DP<2>
J 0
(-1315 2935);
DISPLAY 0.659574 (-1315 2935);
PAINT MONO (-1315 2935);
DISPLAY INVISIBLE (-1315 2935);
FORCEPROP 1 LASTPIN (-1325 2925) BN 2
J 0
(-1375 2935);
DISPLAY 0.617021 (-1375 2935);
PAINT PINK (-1375 2935);
FORCEPROP 2 LAST CDS_LIB mstr_standard
J 0
(-1375 2925);
DISPLAY 0.787234 (-1375 2925);
PAINT MONO (-1375 2925);
DISPLAY INVISIBLE (-1375 2925);
FORCEPROP 1 LAST BODY_TYPE PLUMBING
J 0
(-1375 2875);
DISPLAY 1.234043 (-1375 2875);
PAINT GREEN (-1375 2875);
DISPLAY INVISIBLE (-1375 2875);
FORCEPROP 1 LAST HDL_TAP TRUE
J 0
(-1050 2800);
DISPLAY 1.234043 (-1050 2800);
PAINT GREEN (-1050 2800);
DISPLAY INVISIBLE (-1050 2800);
FORCEPROP 1 LAST PATH I42
J 0
(-1377 2925);
DISPLAY 0.872340 (-1377 2925);
PAINT GREEN (-1377 2925);
DISPLAY INVISIBLE (-1377 2925);
FORCEADD TAP..6
(-1375 3025);
FORCEPROP 3 LASTPIN (-1325 3025) SIG_NAME M_G_CLK_DP<3>
J 0
(-1315 3035);
DISPLAY 0.659574 (-1315 3035);
PAINT MONO (-1315 3035);
DISPLAY INVISIBLE (-1315 3035);
FORCEPROP 1 LASTPIN (-1325 3025) BN 3
J 0
(-1375 3035);
DISPLAY 0.617021 (-1375 3035);
PAINT PINK (-1375 3035);
FORCEPROP 2 LAST CDS_LIB mstr_standard
J 0
(-1375 3025);
DISPLAY 0.787234 (-1375 3025);
PAINT MONO (-1375 3025);
DISPLAY INVISIBLE (-1375 3025);
FORCEPROP 1 LAST BODY_TYPE PLUMBING
J 0
(-1375 2975);
DISPLAY 1.234043 (-1375 2975);
PAINT GREEN (-1375 2975);
DISPLAY INVISIBLE (-1375 2975);
FORCEPROP 1 LAST HDL_TAP TRUE
J 0
(-1050 2900);
DISPLAY 1.234043 (-1050 2900);
PAINT GREEN (-1050 2900);
DISPLAY INVISIBLE (-1050 2900);
FORCEPROP 1 LAST PATH I43
J 0
(-1377 3025);
DISPLAY 0.872340 (-1377 3025);
PAINT GREEN (-1377 3025);
DISPLAY INVISIBLE (-1377 3025);
FORCEADD TAP..6
(-1375 3125);
FORCEPROP 3 LASTPIN (-1325 3125) SIG_NAME M_G_BG<0>
J 0
(-1315 3135);
DISPLAY 0.659574 (-1315 3135);
PAINT MONO (-1315 3135);
DISPLAY INVISIBLE (-1315 3135);
FORCEPROP 1 LASTPIN (-1325 3125) BN 0
J 0
(-1375 3135);
DISPLAY 0.617021 (-1375 3135);
PAINT PINK (-1375 3135);
FORCEPROP 2 LAST CDS_LIB mstr_standard
J 0
(-1375 3125);
DISPLAY 0.787234 (-1375 3125);
PAINT MONO (-1375 3125);
DISPLAY INVISIBLE (-1375 3125);
FORCEPROP 1 LAST BODY_TYPE PLUMBING
J 0
(-1375 3075);
DISPLAY 1.234043 (-1375 3075);
PAINT GREEN (-1375 3075);
DISPLAY INVISIBLE (-1375 3075);
FORCEPROP 1 LAST HDL_TAP TRUE
J 0
(-1050 3000);
DISPLAY 1.234043 (-1050 3000);
PAINT GREEN (-1050 3000);
DISPLAY INVISIBLE (-1050 3000);
FORCEPROP 1 LAST PATH I44
J 0
(-1377 3125);
DISPLAY 0.872340 (-1377 3125);
PAINT GREEN (-1377 3125);
DISPLAY INVISIBLE (-1377 3125);
FORCEADD TAP..6
(-1375 3225);
FORCEPROP 3 LASTPIN (-1325 3225) SIG_NAME M_G_BA<0>
J 0
(-1315 3235);
DISPLAY 0.659574 (-1315 3235);
PAINT MONO (-1315 3235);
DISPLAY INVISIBLE (-1315 3235);
FORCEPROP 1 LASTPIN (-1325 3225) BN 0
J 0
(-1375 3235);
DISPLAY 0.617021 (-1375 3235);
PAINT PINK (-1375 3235);
FORCEPROP 2 LAST CDS_LIB mstr_standard
J 0
(-1375 3225);
DISPLAY 0.787234 (-1375 3225);
PAINT MONO (-1375 3225);
DISPLAY INVISIBLE (-1375 3225);
FORCEPROP 1 LAST BODY_TYPE PLUMBING
J 0
(-1375 3175);
DISPLAY 1.234043 (-1375 3175);
PAINT GREEN (-1375 3175);
DISPLAY INVISIBLE (-1375 3175);
FORCEPROP 1 LAST HDL_TAP TRUE
J 0
(-1050 3100);
DISPLAY 1.234043 (-1050 3100);
PAINT GREEN (-1050 3100);
DISPLAY INVISIBLE (-1050 3100);
FORCEPROP 1 LAST PATH I45
J 0
(-1377 3225);
DISPLAY 0.872340 (-1377 3225);
PAINT GREEN (-1377 3225);
DISPLAY INVISIBLE (-1377 3225);
FORCEADD TAP..6
(-1375 3175);
FORCEPROP 3 LASTPIN (-1325 3175) SIG_NAME M_G_BG<1>
J 0
(-1315 3185);
DISPLAY 0.659574 (-1315 3185);
PAINT MONO (-1315 3185);
DISPLAY INVISIBLE (-1315 3185);
FORCEPROP 1 LASTPIN (-1325 3175) BN 1
J 0
(-1375 3185);
DISPLAY 0.617021 (-1375 3185);
PAINT PINK (-1375 3185);
FORCEPROP 2 LAST CDS_LIB mstr_standard
J 0
(-1375 3175);
DISPLAY 0.787234 (-1375 3175);
PAINT MONO (-1375 3175);
DISPLAY INVISIBLE (-1375 3175);
FORCEPROP 1 LAST BODY_TYPE PLUMBING
J 0
(-1375 3125);
DISPLAY 1.234043 (-1375 3125);
PAINT GREEN (-1375 3125);
DISPLAY INVISIBLE (-1375 3125);
FORCEPROP 1 LAST HDL_TAP TRUE
J 0
(-1050 3050);
DISPLAY 1.234043 (-1050 3050);
PAINT GREEN (-1050 3050);
DISPLAY INVISIBLE (-1050 3050);
FORCEPROP 1 LAST PATH I46
J 0
(-1377 3175);
DISPLAY 0.872340 (-1377 3175);
PAINT GREEN (-1377 3175);
DISPLAY INVISIBLE (-1377 3175);
FORCEADD TAP..6
(-1375 3275);
FORCEPROP 3 LASTPIN (-1325 3275) SIG_NAME M_G_BA<1>
J 0
(-1315 3285);
DISPLAY 0.659574 (-1315 3285);
PAINT MONO (-1315 3285);
DISPLAY INVISIBLE (-1315 3285);
FORCEPROP 1 LASTPIN (-1325 3275) BN 1
J 0
(-1375 3285);
DISPLAY 0.617021 (-1375 3285);
PAINT PINK (-1375 3285);
FORCEPROP 2 LAST CDS_LIB mstr_standard
J 0
(-1375 3275);
DISPLAY 0.787234 (-1375 3275);
PAINT MONO (-1375 3275);
DISPLAY INVISIBLE (-1375 3275);
FORCEPROP 1 LAST BODY_TYPE PLUMBING
J 0
(-1375 3225);
DISPLAY 1.234043 (-1375 3225);
PAINT GREEN (-1375 3225);
DISPLAY INVISIBLE (-1375 3225);
FORCEPROP 1 LAST HDL_TAP TRUE
J 0
(-1050 3150);
DISPLAY 1.234043 (-1050 3150);
PAINT GREEN (-1050 3150);
DISPLAY INVISIBLE (-1050 3150);
FORCEPROP 1 LAST PATH I47
J 0
(-1377 3275);
DISPLAY 0.872340 (-1377 3275);
PAINT GREEN (-1377 3275);
DISPLAY INVISIBLE (-1377 3275);
FORCEADD TAP..6
(-1375 3375);
FORCEPROP 3 LASTPIN (-1325 3375) SIG_NAME M_G_MA<0>
J 0
(-1315 3385);
DISPLAY 0.659574 (-1315 3385);
PAINT MONO (-1315 3385);
DISPLAY INVISIBLE (-1315 3385);
FORCEPROP 1 LASTPIN (-1325 3375) BN 0
J 0
(-1375 3385);
DISPLAY 0.617021 (-1375 3385);
PAINT PINK (-1375 3385);
FORCEPROP 2 LAST CDS_LIB mstr_standard
J 2
(-1375 3375);
DISPLAY 0.787234 (-1375 3375);
PAINT MONO (-1375 3375);
DISPLAY INVISIBLE (-1375 3375);
FORCEPROP 1 LAST BODY_TYPE PLUMBING
J 0
(-1375 3325);
DISPLAY 1.234043 (-1375 3325);
PAINT GREEN (-1375 3325);
DISPLAY INVISIBLE (-1375 3325);
FORCEPROP 1 LAST HDL_TAP TRUE
J 0
(-1050 3250);
DISPLAY 1.234043 (-1050 3250);
PAINT GREEN (-1050 3250);
DISPLAY INVISIBLE (-1050 3250);
FORCEPROP 1 LAST PATH I48
J 0
(-1377 3375);
DISPLAY 0.872340 (-1377 3375);
PAINT GREEN (-1377 3375);
DISPLAY INVISIBLE (-1377 3375);
FORCEADD TAP..6
(-1375 3475);
FORCEPROP 3 LASTPIN (-1325 3475) SIG_NAME M_G_MA<2>
J 0
(-1315 3485);
DISPLAY 0.659574 (-1315 3485);
PAINT MONO (-1315 3485);
DISPLAY INVISIBLE (-1315 3485);
FORCEPROP 1 LASTPIN (-1325 3475) BN 2
J 0
(-1375 3485);
DISPLAY 0.617021 (-1375 3485);
PAINT PINK (-1375 3485);
FORCEPROP 2 LAST CDS_LIB mstr_standard
J 2
(-1375 3475);
DISPLAY 0.787234 (-1375 3475);
PAINT MONO (-1375 3475);
DISPLAY INVISIBLE (-1375 3475);
FORCEPROP 1 LAST BODY_TYPE PLUMBING
J 0
(-1375 3425);
DISPLAY 1.234043 (-1375 3425);
PAINT GREEN (-1375 3425);
DISPLAY INVISIBLE (-1375 3425);
FORCEPROP 1 LAST HDL_TAP TRUE
J 0
(-1050 3350);
DISPLAY 1.234043 (-1050 3350);
PAINT GREEN (-1050 3350);
DISPLAY INVISIBLE (-1050 3350);
FORCEPROP 1 LAST PATH I49
J 0
(-1377 3475);
DISPLAY 0.872340 (-1377 3475);
PAINT GREEN (-1377 3475);
DISPLAY INVISIBLE (-1377 3475);
FORCEADD PVPP_GHJ..1
(-3325 1575);
FORCEPROP 3 LASTPIN (-3325 1525) SIG_NAME PVPP_GHJ\g
J 0
(-3315 1535);
DISPLAY 0.659574 (-3315 1535);
PAINT MONO (-3315 1535);
DISPLAY INVISIBLE (-3315 1535);
FORCEPROP 1 LAST VOLTAGE 2.5V
J 0
(-3370 1532);
DISPLAY 0.340426 (-3370 1532);
PAINT SKYBLUE (-3370 1532);
DISPLAY INVISIBLE (-3370 1532);
FORCEPROP 0 LAST BOM_COST MEM
J 0
(-3325 1675);
PAINT ORANGE (-3325 1675);
DISPLAY INVISIBLE (-3325 1675);
FORCEPROP 2 LAST CDS_LIB mstr_symbols
J 0
(-3325 1575);
PAINT ORANGE (-3325 1575);
DISPLAY INVISIBLE (-3325 1575);
FORCEPROP 1 LAST BODY_TYPE PLUMBING
J 0
(-3370 1532);
DISPLAY 0.340426 (-3370 1532);
PAINT GREEN (-3370 1532);
DISPLAY INVISIBLE (-3370 1532);
FORCEPROP 1 LAST PATH I5
J 0
(-3275 1600);
DISPLAY 0.872340 (-3275 1600);
PAINT AQUA (-3275 1600);
DISPLAY INVISIBLE (-3275 1600);
FORCEPROP 2 LAST ROOM DDR4_GH_G
J 0
(-3325 1675);
PAINT ORANGE (-3325 1675);
DISPLAY INVISIBLE (-3325 1675);
FORCEPROP 1 LAST HDL_POWER PVPP_GHJ
J 1
(-3325 1625);
DISPLAY 0.872340 (-3325 1625);
PAINT GREEN (-3325 1625);
DISPLAY INVISIBLE (-3325 1625);
FORCEADD TAP..6
(-1375 3425);
FORCEPROP 3 LASTPIN (-1325 3425) SIG_NAME M_G_MA<1>
J 0
(-1315 3435);
DISPLAY 0.659574 (-1315 3435);
PAINT MONO (-1315 3435);
DISPLAY INVISIBLE (-1315 3435);
FORCEPROP 1 LASTPIN (-1325 3425) BN 1
J 0
(-1375 3435);
DISPLAY 0.617021 (-1375 3435);
PAINT PINK (-1375 3435);
FORCEPROP 2 LAST CDS_LIB mstr_standard
J 2
(-1375 3425);
DISPLAY 0.787234 (-1375 3425);
PAINT MONO (-1375 3425);
DISPLAY INVISIBLE (-1375 3425);
FORCEPROP 1 LAST BODY_TYPE PLUMBING
J 0
(-1375 3375);
DISPLAY 1.234043 (-1375 3375);
PAINT GREEN (-1375 3375);
DISPLAY INVISIBLE (-1375 3375);
FORCEPROP 1 LAST HDL_TAP TRUE
J 0
(-1050 3300);
DISPLAY 1.234043 (-1050 3300);
PAINT GREEN (-1050 3300);
DISPLAY INVISIBLE (-1050 3300);
FORCEPROP 1 LAST PATH I50
J 0
(-1377 3425);
DISPLAY 0.872340 (-1377 3425);
PAINT GREEN (-1377 3425);
DISPLAY INVISIBLE (-1377 3425);
FORCEADD TAP..6
(-1375 3575);
FORCEPROP 3 LASTPIN (-1325 3575) SIG_NAME M_G_MA<4>
J 0
(-1315 3585);
DISPLAY 0.659574 (-1315 3585);
PAINT MONO (-1315 3585);
DISPLAY INVISIBLE (-1315 3585);
FORCEPROP 1 LASTPIN (-1325 3575) BN 4
J 0
(-1375 3585);
DISPLAY 0.617021 (-1375 3585);
PAINT PINK (-1375 3585);
FORCEPROP 2 LAST CDS_LIB mstr_standard
J 2
(-1375 3575);
DISPLAY 0.787234 (-1375 3575);
PAINT MONO (-1375 3575);
DISPLAY INVISIBLE (-1375 3575);
FORCEPROP 1 LAST BODY_TYPE PLUMBING
J 0
(-1375 3525);
DISPLAY 1.234043 (-1375 3525);
PAINT GREEN (-1375 3525);
DISPLAY INVISIBLE (-1375 3525);
FORCEPROP 1 LAST HDL_TAP TRUE
J 0
(-1050 3450);
DISPLAY 1.234043 (-1050 3450);
PAINT GREEN (-1050 3450);
DISPLAY INVISIBLE (-1050 3450);
FORCEPROP 1 LAST PATH I51
J 0
(-1377 3575);
DISPLAY 0.872340 (-1377 3575);
PAINT GREEN (-1377 3575);
DISPLAY INVISIBLE (-1377 3575);
FORCEADD TAP..6
(-1375 3525);
FORCEPROP 3 LASTPIN (-1325 3525) SIG_NAME M_G_MA<3>
J 0
(-1315 3535);
DISPLAY 0.659574 (-1315 3535);
PAINT MONO (-1315 3535);
DISPLAY INVISIBLE (-1315 3535);
FORCEPROP 1 LASTPIN (-1325 3525) BN 3
J 0
(-1375 3535);
DISPLAY 0.617021 (-1375 3535);
PAINT PINK (-1375 3535);
FORCEPROP 2 LAST CDS_LIB mstr_standard
J 2
(-1375 3525);
DISPLAY 0.787234 (-1375 3525);
PAINT MONO (-1375 3525);
DISPLAY INVISIBLE (-1375 3525);
FORCEPROP 1 LAST BODY_TYPE PLUMBING
J 0
(-1375 3475);
DISPLAY 1.234043 (-1375 3475);
PAINT GREEN (-1375 3475);
DISPLAY INVISIBLE (-1375 3475);
FORCEPROP 1 LAST HDL_TAP TRUE
J 0
(-1050 3400);
DISPLAY 1.234043 (-1050 3400);
PAINT GREEN (-1050 3400);
DISPLAY INVISIBLE (-1050 3400);
FORCEPROP 1 LAST PATH I52
J 0
(-1377 3525);
DISPLAY 0.872340 (-1377 3525);
PAINT GREEN (-1377 3525);
DISPLAY INVISIBLE (-1377 3525);
FORCEADD TAP..6
(-1375 3625);
FORCEPROP 3 LASTPIN (-1325 3625) SIG_NAME M_G_MA<5>
J 0
(-1315 3635);
DISPLAY 0.659574 (-1315 3635);
PAINT MONO (-1315 3635);
DISPLAY INVISIBLE (-1315 3635);
FORCEPROP 1 LASTPIN (-1325 3625) BN 5
J 0
(-1375 3635);
DISPLAY 0.617021 (-1375 3635);
PAINT PINK (-1375 3635);
FORCEPROP 2 LAST CDS_LIB mstr_standard
J 2
(-1375 3625);
DISPLAY 0.787234 (-1375 3625);
PAINT MONO (-1375 3625);
DISPLAY INVISIBLE (-1375 3625);
FORCEPROP 1 LAST BODY_TYPE PLUMBING
J 0
(-1375 3575);
DISPLAY 1.234043 (-1375 3575);
PAINT GREEN (-1375 3575);
DISPLAY INVISIBLE (-1375 3575);
FORCEPROP 1 LAST HDL_TAP TRUE
J 0
(-1050 3500);
DISPLAY 1.234043 (-1050 3500);
PAINT GREEN (-1050 3500);
DISPLAY INVISIBLE (-1050 3500);
FORCEPROP 1 LAST PATH I53
J 0
(-1377 3625);
DISPLAY 0.872340 (-1377 3625);
PAINT GREEN (-1377 3625);
DISPLAY INVISIBLE (-1377 3625);
FORCEADD TAP..6
(-1375 3675);
FORCEPROP 3 LASTPIN (-1325 3675) SIG_NAME M_G_MA<6>
J 0
(-1315 3685);
DISPLAY 0.659574 (-1315 3685);
PAINT MONO (-1315 3685);
DISPLAY INVISIBLE (-1315 3685);
FORCEPROP 1 LASTPIN (-1325 3675) BN 6
J 0
(-1375 3685);
DISPLAY 0.617021 (-1375 3685);
PAINT PINK (-1375 3685);
FORCEPROP 2 LAST CDS_LIB mstr_standard
J 2
(-1375 3675);
DISPLAY 0.787234 (-1375 3675);
PAINT MONO (-1375 3675);
DISPLAY INVISIBLE (-1375 3675);
FORCEPROP 1 LAST BODY_TYPE PLUMBING
J 0
(-1375 3625);
DISPLAY 1.234043 (-1375 3625);
PAINT GREEN (-1375 3625);
DISPLAY INVISIBLE (-1375 3625);
FORCEPROP 1 LAST HDL_TAP TRUE
J 0
(-1050 3550);
DISPLAY 1.234043 (-1050 3550);
PAINT GREEN (-1050 3550);
DISPLAY INVISIBLE (-1050 3550);
FORCEPROP 1 LAST PATH I54
J 0
(-1377 3675);
DISPLAY 0.872340 (-1377 3675);
PAINT GREEN (-1377 3675);
DISPLAY INVISIBLE (-1377 3675);
FORCEADD TAP..6
(-1375 3725);
FORCEPROP 3 LASTPIN (-1325 3725) SIG_NAME M_G_MA<7>
J 0
(-1315 3735);
DISPLAY 0.659574 (-1315 3735);
PAINT MONO (-1315 3735);
DISPLAY INVISIBLE (-1315 3735);
FORCEPROP 1 LASTPIN (-1325 3725) BN 7
J 0
(-1375 3735);
DISPLAY 0.617021 (-1375 3735);
PAINT PINK (-1375 3735);
FORCEPROP 2 LAST CDS_LIB mstr_standard
J 2
(-1375 3725);
DISPLAY 0.787234 (-1375 3725);
PAINT MONO (-1375 3725);
DISPLAY INVISIBLE (-1375 3725);
FORCEPROP 1 LAST BODY_TYPE PLUMBING
J 0
(-1375 3675);
DISPLAY 1.234043 (-1375 3675);
PAINT GREEN (-1375 3675);
DISPLAY INVISIBLE (-1375 3675);
FORCEPROP 1 LAST HDL_TAP TRUE
J 0
(-1050 3600);
DISPLAY 1.234043 (-1050 3600);
PAINT GREEN (-1050 3600);
DISPLAY INVISIBLE (-1050 3600);
FORCEPROP 1 LAST PATH I55
J 0
(-1377 3725);
DISPLAY 0.872340 (-1377 3725);
PAINT GREEN (-1377 3725);
DISPLAY INVISIBLE (-1377 3725);
FORCEADD TAP..6
(-1375 3825);
FORCEPROP 3 LASTPIN (-1325 3825) SIG_NAME M_G_MA<9>
J 0
(-1315 3835);
DISPLAY 0.659574 (-1315 3835);
PAINT MONO (-1315 3835);
DISPLAY INVISIBLE (-1315 3835);
FORCEPROP 1 LASTPIN (-1325 3825) BN 9
J 0
(-1375 3835);
DISPLAY 0.617021 (-1375 3835);
PAINT PINK (-1375 3835);
FORCEPROP 2 LAST CDS_LIB mstr_standard
J 2
(-1375 3825);
DISPLAY 0.787234 (-1375 3825);
PAINT MONO (-1375 3825);
DISPLAY INVISIBLE (-1375 3825);
FORCEPROP 1 LAST BODY_TYPE PLUMBING
J 0
(-1375 3775);
DISPLAY 1.234043 (-1375 3775);
PAINT GREEN (-1375 3775);
DISPLAY INVISIBLE (-1375 3775);
FORCEPROP 1 LAST HDL_TAP TRUE
J 0
(-1050 3700);
DISPLAY 1.234043 (-1050 3700);
PAINT GREEN (-1050 3700);
DISPLAY INVISIBLE (-1050 3700);
FORCEPROP 1 LAST PATH I56
J 0
(-1377 3825);
DISPLAY 0.872340 (-1377 3825);
PAINT GREEN (-1377 3825);
DISPLAY INVISIBLE (-1377 3825);
FORCEADD TAP..6
(-1375 3775);
FORCEPROP 3 LASTPIN (-1325 3775) SIG_NAME M_G_MA<8>
J 0
(-1315 3785);
DISPLAY 0.659574 (-1315 3785);
PAINT MONO (-1315 3785);
DISPLAY INVISIBLE (-1315 3785);
FORCEPROP 1 LASTPIN (-1325 3775) BN 8
J 0
(-1375 3785);
DISPLAY 0.617021 (-1375 3785);
PAINT PINK (-1375 3785);
FORCEPROP 2 LAST CDS_LIB mstr_standard
J 2
(-1375 3775);
DISPLAY 0.787234 (-1375 3775);
PAINT MONO (-1375 3775);
DISPLAY INVISIBLE (-1375 3775);
FORCEPROP 1 LAST BODY_TYPE PLUMBING
J 0
(-1375 3725);
DISPLAY 1.234043 (-1375 3725);
PAINT GREEN (-1375 3725);
DISPLAY INVISIBLE (-1375 3725);
FORCEPROP 1 LAST HDL_TAP TRUE
J 0
(-1050 3650);
DISPLAY 1.234043 (-1050 3650);
PAINT GREEN (-1050 3650);
DISPLAY INVISIBLE (-1050 3650);
FORCEPROP 1 LAST PATH I57
J 0
(-1377 3775);
DISPLAY 0.872340 (-1377 3775);
PAINT GREEN (-1377 3775);
DISPLAY INVISIBLE (-1377 3775);
FORCEADD TAP..6
(-1375 3875);
FORCEPROP 3 LASTPIN (-1325 3875) SIG_NAME M_G_MA<10>
J 0
(-1315 3885);
DISPLAY 0.659574 (-1315 3885);
PAINT MONO (-1315 3885);
DISPLAY INVISIBLE (-1315 3885);
FORCEPROP 1 LASTPIN (-1325 3875) BN 10
J 0
(-1375 3885);
DISPLAY 0.617021 (-1375 3885);
PAINT PINK (-1375 3885);
FORCEPROP 2 LAST CDS_LIB mstr_standard
J 2
(-1375 3875);
DISPLAY 0.787234 (-1375 3875);
PAINT MONO (-1375 3875);
DISPLAY INVISIBLE (-1375 3875);
FORCEPROP 1 LAST BODY_TYPE PLUMBING
J 0
(-1375 3825);
DISPLAY 1.234043 (-1375 3825);
PAINT GREEN (-1375 3825);
DISPLAY INVISIBLE (-1375 3825);
FORCEPROP 1 LAST HDL_TAP TRUE
J 0
(-1050 3750);
DISPLAY 1.234043 (-1050 3750);
PAINT GREEN (-1050 3750);
DISPLAY INVISIBLE (-1050 3750);
FORCEPROP 1 LAST PATH I58
J 0
(-1377 3875);
DISPLAY 0.872340 (-1377 3875);
PAINT GREEN (-1377 3875);
DISPLAY INVISIBLE (-1377 3875);
FORCEADD TAP..6
R 2
(125 1075);
FORCEPROP 3 LASTPIN (75 1075) SIG_NAME M_G_DQ<0>
J 0
(85 1085);
DISPLAY 0.659574 (85 1085);
PAINT MONO (85 1085);
DISPLAY INVISIBLE (85 1085);
FORCEPROP 1 LASTPIN (75 1075) BN 0
J 2
(125 1085);
DISPLAY 0.617021 (125 1085);
PAINT PINK (125 1085);
FORCEPROP 2 LAST CDS_LIB mstr_standard
J 2
(125 1075);
DISPLAY 0.787234 (125 1075);
PAINT MONO (125 1075);
DISPLAY INVISIBLE (125 1075);
FORCEPROP 1 LAST BODY_TYPE PLUMBING
J 2
(125 1025);
DISPLAY 1.234043 (125 1025);
PAINT GREEN (125 1025);
DISPLAY INVISIBLE (125 1025);
FORCEPROP 1 LAST HDL_TAP TRUE
J 2
(-200 950);
DISPLAY 1.234043 (-200 950);
PAINT GREEN (-200 950);
DISPLAY INVISIBLE (-200 950);
FORCEPROP 1 LAST PATH I59
J 2
(127 1075);
DISPLAY 0.872340 (127 1075);
PAINT GREEN (127 1075);
DISPLAY INVISIBLE (127 1075);
FORCEADD OFFPAGE..5
(-2350 1875);
FORCEPROP 2 LAST $XR0 43 
J 0
(-2574 1875);
DISPLAY 0.638298 (-2574 1875);
PAINT MONO (-2574 1875);
FORCEPROP 2 LAST $XR1 44 
J 0
(-2664 1875);
DISPLAY 0.638298 (-2664 1875);
PAINT MONO (-2664 1875);
FORCEPROP 2 LAST $XR2 45 
J 0
(-2754 1875);
DISPLAY 0.638298 (-2754 1875);
PAINT MONO (-2754 1875);
FORCEPROP 2 LAST $XR3 46 
J 0
(-2844 1875);
DISPLAY 0.638298 (-2844 1875);
PAINT MONO (-2844 1875);
FORCEPROP 2 LAST $XR4 47 
J 0
(-2934 1875);
DISPLAY 0.638298 (-2934 1875);
PAINT MONO (-2934 1875);
FORCEPROP 2 LAST $XR5 48 
J 0
(-3024 1875);
DISPLAY 0.638298 (-3024 1875);
PAINT MONO (-3024 1875);
FORCEPROP 2 LAST $XR6 49 
J 0
(-3114 1875);
DISPLAY 0.638298 (-3114 1875);
PAINT MONO (-3114 1875);
FORCEPROP 2 LAST $XR7 50 
J 0
(-3204 1875);
DISPLAY 0.638298 (-3204 1875);
PAINT MONO (-3204 1875);
FORCEPROP 2 LAST $XR8 51 
J 0
(-3294 1875);
DISPLAY 0.638298 (-3294 1875);
PAINT MONO (-3294 1875);
FORCEPROP 2 LAST $XR9 52 
J 0
(-3384 1875);
DISPLAY 0.638298 (-3384 1875);
PAINT MONO (-3384 1875);
FORCEPROP 2 LAST $XR10 53 
J 0
(-2574 1839);
DISPLAY 0.638298 (-2574 1839);
PAINT MONO (-2574 1839);
FORCEPROP 2 LAST $XR11 54 
J 0
(-2664 1839);
DISPLAY 0.638298 (-2664 1839);
PAINT MONO (-2664 1839);
FORCEPROP 2 LAST $XR12 77 
J 0
(-2754 1839);
DISPLAY 0.638298 (-2754 1839);
PAINT MONO (-2754 1839);
FORCEPROP 2 LAST $XR13 79 
J 0
(-2844 1839);
DISPLAY 0.638298 (-2844 1839);
PAINT MONO (-2844 1839);
FORCEPROP 2 LAST $XR14 80 
J 0
(-2934 1839);
DISPLAY 0.638298 (-2934 1839);
PAINT MONO (-2934 1839);
FORCEPROP 2 LAST $XR15 81 
J 0
(-3024 1839);
DISPLAY 0.638298 (-3024 1839);
PAINT MONO (-3024 1839);
FORCEPROP 2 LAST $XR16 82 
J 0
(-3114 1839);
DISPLAY 0.638298 (-3114 1839);
PAINT MONO (-3114 1839);
FORCEPROP 2 LAST $XR17 83 
J 0
(-3204 1839);
DISPLAY 0.638298 (-3204 1839);
PAINT MONO (-3204 1839);
FORCEPROP 2 LAST $XR18 84 
J 0
(-3294 1839);
DISPLAY 0.638298 (-3294 1839);
PAINT MONO (-3294 1839);
FORCEPROP 2 LAST $XR19 85 
J 0
(-3384 1839);
DISPLAY 0.638298 (-3384 1839);
PAINT MONO (-3384 1839);
FORCEPROP 2 LAST $XR20 86 
J 0
(-2574 1911);
DISPLAY 0.638298 (-2574 1911);
PAINT MONO (-2574 1911);
FORCEPROP 2 LAST $XR21 87 
J 0
(-2664 1911);
DISPLAY 0.638298 (-2664 1911);
PAINT MONO (-2664 1911);
FORCEPROP 2 LAST $XR22 88 
J 0
(-2754 1911);
DISPLAY 0.638298 (-2754 1911);
PAINT MONO (-2754 1911);
FORCEPROP 2 LAST $XR23 94 
J 0
(-2844 1911);
DISPLAY 0.638298 (-2844 1911);
PAINT MONO (-2844 1911);
FORCEPROP 2 LAST CDS_LIB mstr_standard
J 0
(-2350 1875);
DISPLAY 0.787234 (-2350 1875);
PAINT MONO (-2350 1875);
DISPLAY INVISIBLE (-2350 1875);
FORCEPROP 1 LAST OFFPAGE TRUE
J 0
(-2025 1750);
DISPLAY 1.404255 (-2025 1750);
PAINT GREEN (-2025 1750);
DISPLAY INVISIBLE (-2025 1750);
FORCEPROP 1 LAST COMMENT_BODY TRUE
J 0
(-2250 1800);
DISPLAY 1.404255 (-2250 1800);
PAINT GREEN (-2250 1800);
DISPLAY INVISIBLE (-2250 1800);
FORCEPROP 2 LAST PATH I6
J 0
(-2550 1925);
DISPLAY 1.021277 (-2550 1925);
PAINT ORANGE (-2550 1925);
DISPLAY INVISIBLE (-2550 1925);
FORCEADD TAP..6
R 2
(125 1125);
FORCEPROP 3 LASTPIN (75 1125) SIG_NAME M_G_DQ<1>
J 0
(85 1135);
DISPLAY 0.659574 (85 1135);
PAINT MONO (85 1135);
DISPLAY INVISIBLE (85 1135);
FORCEPROP 1 LASTPIN (75 1125) BN 1
J 2
(125 1135);
DISPLAY 0.617021 (125 1135);
PAINT PINK (125 1135);
FORCEPROP 2 LAST CDS_LIB mstr_standard
J 2
(125 1125);
DISPLAY 0.787234 (125 1125);
PAINT MONO (125 1125);
DISPLAY INVISIBLE (125 1125);
FORCEPROP 1 LAST BODY_TYPE PLUMBING
J 2
(125 1075);
DISPLAY 1.234043 (125 1075);
PAINT GREEN (125 1075);
DISPLAY INVISIBLE (125 1075);
FORCEPROP 1 LAST HDL_TAP TRUE
J 2
(-200 1000);
DISPLAY 1.234043 (-200 1000);
PAINT GREEN (-200 1000);
DISPLAY INVISIBLE (-200 1000);
FORCEPROP 1 LAST PATH I60
J 2
(127 1125);
DISPLAY 0.872340 (127 1125);
PAINT GREEN (127 1125);
DISPLAY INVISIBLE (127 1125);
FORCEADD TAP..6
R 2
(125 1175);
FORCEPROP 3 LASTPIN (75 1175) SIG_NAME M_G_DQ<2>
J 0
(85 1185);
DISPLAY 0.659574 (85 1185);
PAINT MONO (85 1185);
DISPLAY INVISIBLE (85 1185);
FORCEPROP 1 LASTPIN (75 1175) BN 2
J 2
(125 1185);
DISPLAY 0.617021 (125 1185);
PAINT PINK (125 1185);
FORCEPROP 2 LAST CDS_LIB mstr_standard
J 2
(125 1175);
DISPLAY 0.787234 (125 1175);
PAINT MONO (125 1175);
DISPLAY INVISIBLE (125 1175);
FORCEPROP 1 LAST BODY_TYPE PLUMBING
J 2
(125 1125);
DISPLAY 1.234043 (125 1125);
PAINT GREEN (125 1125);
DISPLAY INVISIBLE (125 1125);
FORCEPROP 1 LAST HDL_TAP TRUE
J 2
(-200 1050);
DISPLAY 1.234043 (-200 1050);
PAINT GREEN (-200 1050);
DISPLAY INVISIBLE (-200 1050);
FORCEPROP 1 LAST PATH I61
J 2
(127 1175);
DISPLAY 0.872340 (127 1175);
PAINT GREEN (127 1175);
DISPLAY INVISIBLE (127 1175);
FORCEADD TAP..6
R 2
(125 1325);
FORCEPROP 3 LASTPIN (75 1325) SIG_NAME M_G_DQ<5>
J 0
(85 1335);
DISPLAY 0.659574 (85 1335);
PAINT MONO (85 1335);
DISPLAY INVISIBLE (85 1335);
FORCEPROP 1 LASTPIN (75 1325) BN 5
J 2
(125 1335);
DISPLAY 0.617021 (125 1335);
PAINT PINK (125 1335);
FORCEPROP 2 LAST CDS_LIB mstr_standard
J 2
(125 1325);
DISPLAY 0.787234 (125 1325);
PAINT MONO (125 1325);
DISPLAY INVISIBLE (125 1325);
FORCEPROP 1 LAST BODY_TYPE PLUMBING
J 2
(125 1275);
DISPLAY 1.234043 (125 1275);
PAINT GREEN (125 1275);
DISPLAY INVISIBLE (125 1275);
FORCEPROP 1 LAST HDL_TAP TRUE
J 2
(-200 1200);
DISPLAY 1.234043 (-200 1200);
PAINT GREEN (-200 1200);
DISPLAY INVISIBLE (-200 1200);
FORCEPROP 1 LAST PATH I62
J 2
(127 1325);
DISPLAY 0.872340 (127 1325);
PAINT GREEN (127 1325);
DISPLAY INVISIBLE (127 1325);
FORCEADD TAP..6
R 2
(125 1275);
FORCEPROP 3 LASTPIN (75 1275) SIG_NAME M_G_DQ<4>
J 0
(85 1285);
DISPLAY 0.659574 (85 1285);
PAINT MONO (85 1285);
DISPLAY INVISIBLE (85 1285);
FORCEPROP 1 LASTPIN (75 1275) BN 4
J 2
(125 1285);
DISPLAY 0.617021 (125 1285);
PAINT PINK (125 1285);
FORCEPROP 2 LAST CDS_LIB mstr_standard
J 2
(125 1275);
DISPLAY 0.787234 (125 1275);
PAINT MONO (125 1275);
DISPLAY INVISIBLE (125 1275);
FORCEPROP 1 LAST BODY_TYPE PLUMBING
J 2
(125 1225);
DISPLAY 1.234043 (125 1225);
PAINT GREEN (125 1225);
DISPLAY INVISIBLE (125 1225);
FORCEPROP 1 LAST HDL_TAP TRUE
J 2
(-200 1150);
DISPLAY 1.234043 (-200 1150);
PAINT GREEN (-200 1150);
DISPLAY INVISIBLE (-200 1150);
FORCEPROP 1 LAST PATH I63
J 2
(127 1275);
DISPLAY 0.872340 (127 1275);
PAINT GREEN (127 1275);
DISPLAY INVISIBLE (127 1275);
FORCEADD TAP..6
R 2
(125 1225);
FORCEPROP 3 LASTPIN (75 1225) SIG_NAME M_G_DQ<3>
J 0
(85 1235);
DISPLAY 0.659574 (85 1235);
PAINT MONO (85 1235);
DISPLAY INVISIBLE (85 1235);
FORCEPROP 1 LASTPIN (75 1225) BN 3
J 2
(125 1235);
DISPLAY 0.617021 (125 1235);
PAINT PINK (125 1235);
FORCEPROP 2 LAST CDS_LIB mstr_standard
J 2
(125 1225);
DISPLAY 0.787234 (125 1225);
PAINT MONO (125 1225);
DISPLAY INVISIBLE (125 1225);
FORCEPROP 1 LAST BODY_TYPE PLUMBING
J 2
(125 1175);
DISPLAY 1.234043 (125 1175);
PAINT GREEN (125 1175);
DISPLAY INVISIBLE (125 1175);
FORCEPROP 1 LAST HDL_TAP TRUE
J 2
(-200 1100);
DISPLAY 1.234043 (-200 1100);
PAINT GREEN (-200 1100);
DISPLAY INVISIBLE (-200 1100);
FORCEPROP 1 LAST PATH I64
J 2
(127 1225);
DISPLAY 0.872340 (127 1225);
PAINT GREEN (127 1225);
DISPLAY INVISIBLE (127 1225);
FORCEADD TAP..6
R 2
(125 1375);
FORCEPROP 3 LASTPIN (75 1375) SIG_NAME M_G_DQ<6>
J 0
(85 1385);
DISPLAY 0.659574 (85 1385);
PAINT MONO (85 1385);
DISPLAY INVISIBLE (85 1385);
FORCEPROP 1 LASTPIN (75 1375) BN 6
J 2
(125 1385);
DISPLAY 0.617021 (125 1385);
PAINT PINK (125 1385);
FORCEPROP 2 LAST CDS_LIB mstr_standard
J 2
(125 1375);
DISPLAY 0.787234 (125 1375);
PAINT MONO (125 1375);
DISPLAY INVISIBLE (125 1375);
FORCEPROP 1 LAST BODY_TYPE PLUMBING
J 2
(125 1325);
DISPLAY 1.234043 (125 1325);
PAINT GREEN (125 1325);
DISPLAY INVISIBLE (125 1325);
FORCEPROP 1 LAST HDL_TAP TRUE
J 2
(-200 1250);
DISPLAY 1.234043 (-200 1250);
PAINT GREEN (-200 1250);
DISPLAY INVISIBLE (-200 1250);
FORCEPROP 1 LAST PATH I65
J 2
(127 1375);
DISPLAY 0.872340 (127 1375);
PAINT GREEN (127 1375);
DISPLAY INVISIBLE (127 1375);
FORCEADD TAP..6
R 2
(125 1425);
FORCEPROP 3 LASTPIN (75 1425) SIG_NAME M_G_DQ<7>
J 0
(85 1435);
DISPLAY 0.659574 (85 1435);
PAINT MONO (85 1435);
DISPLAY INVISIBLE (85 1435);
FORCEPROP 1 LASTPIN (75 1425) BN 7
J 2
(125 1435);
DISPLAY 0.617021 (125 1435);
PAINT PINK (125 1435);
FORCEPROP 2 LAST CDS_LIB mstr_standard
J 2
(125 1425);
DISPLAY 0.787234 (125 1425);
PAINT MONO (125 1425);
DISPLAY INVISIBLE (125 1425);
FORCEPROP 1 LAST BODY_TYPE PLUMBING
J 2
(125 1375);
DISPLAY 1.234043 (125 1375);
PAINT GREEN (125 1375);
DISPLAY INVISIBLE (125 1375);
FORCEPROP 1 LAST HDL_TAP TRUE
J 2
(-200 1300);
DISPLAY 1.234043 (-200 1300);
PAINT GREEN (-200 1300);
DISPLAY INVISIBLE (-200 1300);
FORCEPROP 1 LAST PATH I66
J 2
(127 1425);
DISPLAY 0.872340 (127 1425);
PAINT GREEN (127 1425);
DISPLAY INVISIBLE (127 1425);
FORCEADD TAP..6
R 2
(125 1475);
FORCEPROP 3 LASTPIN (75 1475) SIG_NAME M_G_DQ<8>
J 0
(85 1485);
DISPLAY 0.659574 (85 1485);
PAINT MONO (85 1485);
DISPLAY INVISIBLE (85 1485);
FORCEPROP 1 LASTPIN (75 1475) BN 8
J 2
(125 1485);
DISPLAY 0.617021 (125 1485);
PAINT PINK (125 1485);
FORCEPROP 2 LAST CDS_LIB mstr_standard
J 2
(125 1475);
DISPLAY 0.787234 (125 1475);
PAINT MONO (125 1475);
DISPLAY INVISIBLE (125 1475);
FORCEPROP 1 LAST BODY_TYPE PLUMBING
J 2
(125 1425);
DISPLAY 1.234043 (125 1425);
PAINT GREEN (125 1425);
DISPLAY INVISIBLE (125 1425);
FORCEPROP 1 LAST HDL_TAP TRUE
J 2
(-200 1350);
DISPLAY 1.234043 (-200 1350);
PAINT GREEN (-200 1350);
DISPLAY INVISIBLE (-200 1350);
FORCEPROP 1 LAST PATH I67
J 2
(127 1475);
DISPLAY 0.872340 (127 1475);
PAINT GREEN (127 1475);
DISPLAY INVISIBLE (127 1475);
FORCEADD TAP..6
R 2
(125 1525);
FORCEPROP 3 LASTPIN (75 1525) SIG_NAME M_G_DQ<9>
J 0
(85 1535);
DISPLAY 0.659574 (85 1535);
PAINT MONO (85 1535);
DISPLAY INVISIBLE (85 1535);
FORCEPROP 1 LASTPIN (75 1525) BN 9
J 2
(125 1535);
DISPLAY 0.617021 (125 1535);
PAINT PINK (125 1535);
FORCEPROP 2 LAST CDS_LIB mstr_standard
J 2
(125 1525);
DISPLAY 0.787234 (125 1525);
PAINT MONO (125 1525);
DISPLAY INVISIBLE (125 1525);
FORCEPROP 1 LAST BODY_TYPE PLUMBING
J 2
(125 1475);
DISPLAY 1.234043 (125 1475);
PAINT GREEN (125 1475);
DISPLAY INVISIBLE (125 1475);
FORCEPROP 1 LAST HDL_TAP TRUE
J 2
(-200 1400);
DISPLAY 1.234043 (-200 1400);
PAINT GREEN (-200 1400);
DISPLAY INVISIBLE (-200 1400);
FORCEPROP 1 LAST PATH I68
J 2
(127 1525);
DISPLAY 0.872340 (127 1525);
PAINT GREEN (127 1525);
DISPLAY INVISIBLE (127 1525);
FORCEADD TAP..6
R 2
(125 1575);
FORCEPROP 3 LASTPIN (75 1575) SIG_NAME M_G_DQ<10>
J 0
(85 1585);
DISPLAY 0.659574 (85 1585);
PAINT MONO (85 1585);
DISPLAY INVISIBLE (85 1585);
FORCEPROP 1 LASTPIN (75 1575) BN 10
J 2
(125 1585);
DISPLAY 0.617021 (125 1585);
PAINT PINK (125 1585);
FORCEPROP 2 LAST CDS_LIB mstr_standard
J 2
(125 1575);
DISPLAY 0.787234 (125 1575);
PAINT MONO (125 1575);
DISPLAY INVISIBLE (125 1575);
FORCEPROP 1 LAST BODY_TYPE PLUMBING
J 2
(125 1525);
DISPLAY 1.234043 (125 1525);
PAINT GREEN (125 1525);
DISPLAY INVISIBLE (125 1525);
FORCEPROP 1 LAST HDL_TAP TRUE
J 2
(-200 1450);
DISPLAY 1.234043 (-200 1450);
PAINT GREEN (-200 1450);
DISPLAY INVISIBLE (-200 1450);
FORCEPROP 1 LAST PATH I69
J 2
(127 1575);
DISPLAY 0.872340 (127 1575);
PAINT GREEN (127 1575);
DISPLAY INVISIBLE (127 1575);
FORCEADD OFFPAGE..5
(-2200 1575);
FORCEPROP 2 LAST $XR0 77 
J 0
(-2454 1575);
DISPLAY 0.638298 (-2454 1575);
PAINT MONO (-2454 1575);
FORCEPROP 2 LAST $XR1 57 
J 0
(-2544 1575);
DISPLAY 0.638298 (-2544 1575);
PAINT MONO (-2544 1575);
FORCEPROP 2 LAST CDS_LIB mstr_standard
J 0
(-2200 1575);
DISPLAY 0.787234 (-2200 1575);
PAINT MONO (-2200 1575);
DISPLAY INVISIBLE (-2200 1575);
FORCEPROP 1 LAST OFFPAGE TRUE
J 0
(-1875 1450);
DISPLAY 1.404255 (-1875 1450);
PAINT GREEN (-1875 1450);
DISPLAY INVISIBLE (-1875 1450);
FORCEPROP 1 LAST COMMENT_BODY TRUE
J 0
(-2100 1500);
DISPLAY 1.404255 (-2100 1500);
PAINT GREEN (-2100 1500);
DISPLAY INVISIBLE (-2100 1500);
FORCEPROP 2 LAST PATH I7
J 0
(-2450 1625);
DISPLAY 1.021277 (-2450 1625);
PAINT ORANGE (-2450 1625);
DISPLAY INVISIBLE (-2450 1625);
FORCEADD TAP..6
R 2
(125 1725);
FORCEPROP 3 LASTPIN (75 1725) SIG_NAME M_G_DQ<13>
J 0
(85 1735);
DISPLAY 0.659574 (85 1735);
PAINT MONO (85 1735);
DISPLAY INVISIBLE (85 1735);
FORCEPROP 1 LASTPIN (75 1725) BN 13
J 2
(125 1735);
DISPLAY 0.617021 (125 1735);
PAINT PINK (125 1735);
FORCEPROP 2 LAST CDS_LIB mstr_standard
J 2
(125 1725);
DISPLAY 0.787234 (125 1725);
PAINT MONO (125 1725);
DISPLAY INVISIBLE (125 1725);
FORCEPROP 1 LAST BODY_TYPE PLUMBING
J 2
(125 1675);
DISPLAY 1.234043 (125 1675);
PAINT GREEN (125 1675);
DISPLAY INVISIBLE (125 1675);
FORCEPROP 1 LAST HDL_TAP TRUE
J 2
(-200 1600);
DISPLAY 1.234043 (-200 1600);
PAINT GREEN (-200 1600);
DISPLAY INVISIBLE (-200 1600);
FORCEPROP 1 LAST PATH I70
J 2
(127 1725);
DISPLAY 0.872340 (127 1725);
PAINT GREEN (127 1725);
DISPLAY INVISIBLE (127 1725);
FORCEADD TAP..6
R 2
(125 1625);
FORCEPROP 3 LASTPIN (75 1625) SIG_NAME M_G_DQ<11>
J 0
(85 1635);
DISPLAY 0.659574 (85 1635);
PAINT MONO (85 1635);
DISPLAY INVISIBLE (85 1635);
FORCEPROP 1 LASTPIN (75 1625) BN 11
J 2
(125 1635);
DISPLAY 0.617021 (125 1635);
PAINT PINK (125 1635);
FORCEPROP 2 LAST CDS_LIB mstr_standard
J 2
(125 1625);
DISPLAY 0.787234 (125 1625);
PAINT MONO (125 1625);
DISPLAY INVISIBLE (125 1625);
FORCEPROP 1 LAST BODY_TYPE PLUMBING
J 2
(125 1575);
DISPLAY 1.234043 (125 1575);
PAINT GREEN (125 1575);
DISPLAY INVISIBLE (125 1575);
FORCEPROP 1 LAST HDL_TAP TRUE
J 2
(-200 1500);
DISPLAY 1.234043 (-200 1500);
PAINT GREEN (-200 1500);
DISPLAY INVISIBLE (-200 1500);
FORCEPROP 1 LAST PATH I71
J 2
(127 1625);
DISPLAY 0.872340 (127 1625);
PAINT GREEN (127 1625);
DISPLAY INVISIBLE (127 1625);
FORCEADD TAP..6
R 2
(125 1675);
FORCEPROP 3 LASTPIN (75 1675) SIG_NAME M_G_DQ<12>
J 0
(85 1685);
DISPLAY 0.659574 (85 1685);
PAINT MONO (85 1685);
DISPLAY INVISIBLE (85 1685);
FORCEPROP 1 LASTPIN (75 1675) BN 12
J 2
(125 1685);
DISPLAY 0.617021 (125 1685);
PAINT PINK (125 1685);
FORCEPROP 2 LAST CDS_LIB mstr_standard
J 2
(125 1675);
DISPLAY 0.787234 (125 1675);
PAINT MONO (125 1675);
DISPLAY INVISIBLE (125 1675);
FORCEPROP 1 LAST BODY_TYPE PLUMBING
J 2
(125 1625);
DISPLAY 1.234043 (125 1625);
PAINT GREEN (125 1625);
DISPLAY INVISIBLE (125 1625);
FORCEPROP 1 LAST HDL_TAP TRUE
J 2
(-200 1550);
DISPLAY 1.234043 (-200 1550);
PAINT GREEN (-200 1550);
DISPLAY INVISIBLE (-200 1550);
FORCEPROP 1 LAST PATH I72
J 2
(127 1675);
DISPLAY 0.872340 (127 1675);
PAINT GREEN (127 1675);
DISPLAY INVISIBLE (127 1675);
FORCEADD TAP..6
R 2
(125 1775);
FORCEPROP 3 LASTPIN (75 1775) SIG_NAME M_G_DQ<14>
J 0
(85 1785);
DISPLAY 0.659574 (85 1785);
PAINT MONO (85 1785);
DISPLAY INVISIBLE (85 1785);
FORCEPROP 1 LASTPIN (75 1775) BN 14
J 2
(125 1785);
DISPLAY 0.617021 (125 1785);
PAINT PINK (125 1785);
FORCEPROP 2 LAST CDS_LIB mstr_standard
J 2
(125 1775);
DISPLAY 0.787234 (125 1775);
PAINT MONO (125 1775);
DISPLAY INVISIBLE (125 1775);
FORCEPROP 1 LAST BODY_TYPE PLUMBING
J 2
(125 1725);
DISPLAY 1.234043 (125 1725);
PAINT GREEN (125 1725);
DISPLAY INVISIBLE (125 1725);
FORCEPROP 1 LAST HDL_TAP TRUE
J 2
(-200 1650);
DISPLAY 1.234043 (-200 1650);
PAINT GREEN (-200 1650);
DISPLAY INVISIBLE (-200 1650);
FORCEPROP 1 LAST PATH I73
J 2
(127 1775);
DISPLAY 0.872340 (127 1775);
PAINT GREEN (127 1775);
DISPLAY INVISIBLE (127 1775);
FORCEADD TAP..6
R 2
(125 1825);
FORCEPROP 3 LASTPIN (75 1825) SIG_NAME M_G_DQ<15>
J 0
(85 1835);
DISPLAY 0.659574 (85 1835);
PAINT MONO (85 1835);
DISPLAY INVISIBLE (85 1835);
FORCEPROP 1 LASTPIN (75 1825) BN 15
J 2
(125 1835);
DISPLAY 0.617021 (125 1835);
PAINT PINK (125 1835);
FORCEPROP 2 LAST CDS_LIB mstr_standard
J 2
(125 1825);
DISPLAY 0.787234 (125 1825);
PAINT MONO (125 1825);
DISPLAY INVISIBLE (125 1825);
FORCEPROP 1 LAST BODY_TYPE PLUMBING
J 2
(125 1775);
DISPLAY 1.234043 (125 1775);
PAINT GREEN (125 1775);
DISPLAY INVISIBLE (125 1775);
FORCEPROP 1 LAST HDL_TAP TRUE
J 2
(-200 1700);
DISPLAY 1.234043 (-200 1700);
PAINT GREEN (-200 1700);
DISPLAY INVISIBLE (-200 1700);
FORCEPROP 1 LAST PATH I74
J 2
(127 1825);
DISPLAY 0.872340 (127 1825);
PAINT GREEN (127 1825);
DISPLAY INVISIBLE (127 1825);
FORCEADD SCONN288_H44441003..4
(1450 1750);
FORCEPROP 1 LAST LOCATION J9T1
J 0
(1000 2850);
DISPLAY 0.617021 (1000 2850);
PAINT AQUA (1000 2850);
FORCEPROP 1 LAST PART_NUMBER H44441-003
J 0
(1000 700);
DISPLAY 0.617021 (1000 700);
PAINT BLUE (1000 700);
FORCEPROP 1 LAST MATERIAL SCONN
J 0
(1000 2800);
DISPLAY 0.617021 (1000 2800);
PAINT SKYBLUE (1000 2800);
FORCEPROP 2 LASTPIN (950 2300) $PN 77
J 2
(940 2310);
DISPLAY 0.617021 (940 2310);
PAINT ORANGE (940 2310);
FORCEPROP 2 LASTPIN (950 2250) $PN 221
J 2
(940 2260);
DISPLAY 0.617021 (940 2260);
PAINT ORANGE (940 2260);
FORCEPROP 2 LASTPIN (950 2600) $PN 142
J 2
(940 2610);
DISPLAY 0.617021 (940 2610);
PAINT ORANGE (940 2610);
FORCEPROP 2 LASTPIN (950 2550) $PN 143
J 2
(940 2560);
DISPLAY 0.617021 (940 2560);
PAINT ORANGE (940 2560);
FORCEPROP 2 LASTPIN (950 2500) $PN 288
J 2
(940 2510);
DISPLAY 0.617021 (940 2510);
PAINT ORANGE (940 2510);
FORCEPROP 2 LASTPIN (950 2450) $PN 286
J 2
(940 2460);
DISPLAY 0.617021 (940 2460);
PAINT ORANGE (940 2460);
FORCEPROP 2 LASTPIN (950 2400) $PN 287
J 2
(940 2410);
DISPLAY 0.617021 (940 2410);
PAINT ORANGE (940 2410);
FORCEPROP 2 LASTPIN (950 2150) $PN 59
J 2
(940 2160);
DISPLAY 0.617021 (940 2160);
PAINT ORANGE (940 2160);
FORCEPROP 2 LASTPIN (950 2100) $PN 61
J 2
(940 2110);
DISPLAY 0.617021 (940 2110);
PAINT ORANGE (940 2110);
FORCEPROP 2 LASTPIN (950 2050) $PN 64
J 2
(940 2060);
DISPLAY 0.617021 (940 2060);
PAINT ORANGE (940 2060);
FORCEPROP 2 LASTPIN (950 2000) $PN 67
J 2
(940 2010);
DISPLAY 0.617021 (940 2010);
PAINT ORANGE (940 2010);
FORCEPROP 2 LASTPIN (950 1950) $PN 70
J 2
(940 1960);
DISPLAY 0.617021 (940 1960);
PAINT ORANGE (940 1960);
FORCEPROP 2 LASTPIN (950 1900) $PN 73
J 2
(940 1910);
DISPLAY 0.617021 (940 1910);
PAINT ORANGE (940 1910);
FORCEPROP 2 LASTPIN (950 1850) $PN 76
J 2
(940 1860);
DISPLAY 0.617021 (940 1860);
PAINT ORANGE (940 1860);
FORCEPROP 2 LASTPIN (950 1800) $PN 80
J 2
(940 1810);
DISPLAY 0.617021 (940 1810);
PAINT ORANGE (940 1810);
FORCEPROP 2 LASTPIN (950 1750) $PN 83
J 2
(940 1760);
DISPLAY 0.617021 (940 1760);
PAINT ORANGE (940 1760);
FORCEPROP 2 LASTPIN (950 1700) $PN 85
J 2
(940 1710);
DISPLAY 0.617021 (940 1710);
PAINT ORANGE (940 1710);
FORCEPROP 2 LASTPIN (950 1650) $PN 88
J 2
(940 1660);
DISPLAY 0.617021 (940 1660);
PAINT ORANGE (940 1660);
FORCEPROP 2 LASTPIN (950 1600) $PN 90
J 2
(940 1610);
DISPLAY 0.617021 (940 1610);
PAINT ORANGE (940 1610);
FORCEPROP 2 LASTPIN (950 1550) $PN 92
J 2
(940 1560);
DISPLAY 0.617021 (940 1560);
PAINT ORANGE (940 1560);
FORCEPROP 2 LASTPIN (950 1500) $PN 204
J 2
(940 1510);
DISPLAY 0.617021 (940 1510);
PAINT ORANGE (940 1510);
FORCEPROP 2 LASTPIN (950 1450) $PN 206
J 2
(940 1460);
DISPLAY 0.617021 (940 1460);
PAINT ORANGE (940 1460);
FORCEPROP 2 LASTPIN (950 1400) $PN 209
J 2
(940 1410);
DISPLAY 0.617021 (940 1410);
PAINT ORANGE (940 1410);
FORCEPROP 2 LASTPIN (950 1350) $PN 212
J 2
(940 1360);
DISPLAY 0.617021 (940 1360);
PAINT ORANGE (940 1360);
FORCEPROP 2 LASTPIN (950 1300) $PN 215
J 2
(940 1310);
DISPLAY 0.617021 (940 1310);
PAINT ORANGE (940 1310);
FORCEPROP 2 LASTPIN (950 1250) $PN 217
J 2
(940 1260);
DISPLAY 0.617021 (940 1260);
PAINT ORANGE (940 1260);
FORCEPROP 2 LASTPIN (950 1200) $PN 220
J 2
(940 1210);
DISPLAY 0.617021 (940 1210);
PAINT ORANGE (940 1210);
FORCEPROP 2 LASTPIN (950 1150) $PN 223
J 2
(940 1160);
DISPLAY 0.617021 (940 1160);
PAINT ORANGE (940 1160);
FORCEPROP 2 LASTPIN (950 1100) $PN 226
J 2
(940 1110);
DISPLAY 0.617021 (940 1110);
PAINT ORANGE (940 1110);
FORCEPROP 2 LASTPIN (950 1050) $PN 229
J 2
(940 1060);
DISPLAY 0.617021 (940 1060);
PAINT ORANGE (940 1060);
FORCEPROP 2 LASTPIN (950 1000) $PN 231
J 2
(940 1010);
DISPLAY 0.617021 (940 1010);
PAINT ORANGE (940 1010);
FORCEPROP 2 LASTPIN (950 950) $PN 233
J 2
(940 960);
DISPLAY 0.617021 (940 960);
PAINT ORANGE (940 960);
FORCEPROP 2 LASTPIN (950 900) $PN 236
J 2
(940 910);
DISPLAY 0.617021 (940 910);
PAINT ORANGE (940 910);
FORCEPROP 2 LASTPIN (1950 2600) $PN 1
J 0
(1960 2610);
DISPLAY 0.617021 (1960 2610);
PAINT ORANGE (1960 2610);
FORCEPROP 2 LASTPIN (1950 2550) $PN 145
J 0
(1960 2560);
DISPLAY 0.617021 (1960 2560);
PAINT ORANGE (1960 2560);
FORCEPROP 1 LAST PACK_TYPE PIP
J 0
(1000 2900);
PAINT SKYBLUE (1000 2900);
DISPLAY INVISIBLE (1000 2900);
FORCEPROP 2 LAST BOM_COST MEM
J 0
(1450 1750);
PAINT ORANGE (1450 1750);
DISPLAY INVISIBLE (1450 1750);
FORCEPROP 2 LAST CDS_LIB mstr_sconn
J 0
(1450 1750);
PAINT ORANGE (1450 1750);
DISPLAY INVISIBLE (1450 1750);
FORCEPROP 2 LAST SEC_TYPE PIP
J 0
(1000 2900);
DISPLAY 1.021277 (1000 2900);
PAINT ORANGE (1000 2900);
DISPLAY INVISIBLE (1000 2900);
FORCEPROP 2 LAST SEC 4
J 0
(1000 2900);
DISPLAY 0.680851 (1000 2900);
PAINT MONO (1000 2900);
DISPLAY INVISIBLE (1000 2900);
FORCEPROP 2 LAST CDS_LOCATION J9T1
J 0
(1000 2850);
DISPLAY 0.617021 (1000 2850);
PAINT AQUA (1000 2850);
DISPLAY INVISIBLE (1000 2850);
FORCEPROP 1 LAST PATH I75
J 0
(1450 2800);
PAINT GREEN (1450 2800);
DISPLAY INVISIBLE (1450 2800);
FORCEPROP 2 LAST ROOM DDR4_GH_G
J 0
(1450 1750);
PAINT ORANGE (1450 1750);
DISPLAY INVISIBLE (1450 1750);
FORCEADD TAP..6
R 2
(125 1925);
FORCEPROP 3 LASTPIN (75 1925) SIG_NAME M_G_DQ<17>
J 0
(85 1935);
DISPLAY 0.659574 (85 1935);
PAINT MONO (85 1935);
DISPLAY INVISIBLE (85 1935);
FORCEPROP 1 LASTPIN (75 1925) BN 17
J 2
(125 1935);
DISPLAY 0.617021 (125 1935);
PAINT PINK (125 1935);
FORCEPROP 2 LAST CDS_LIB mstr_standard
J 2
(125 1925);
DISPLAY 0.787234 (125 1925);
PAINT MONO (125 1925);
DISPLAY INVISIBLE (125 1925);
FORCEPROP 1 LAST BODY_TYPE PLUMBING
J 2
(125 1875);
DISPLAY 1.234043 (125 1875);
PAINT GREEN (125 1875);
DISPLAY INVISIBLE (125 1875);
FORCEPROP 1 LAST HDL_TAP TRUE
J 2
(-200 1800);
DISPLAY 1.234043 (-200 1800);
PAINT GREEN (-200 1800);
DISPLAY INVISIBLE (-200 1800);
FORCEPROP 1 LAST PATH I76
J 2
(127 1925);
DISPLAY 0.872340 (127 1925);
PAINT GREEN (127 1925);
DISPLAY INVISIBLE (127 1925);
FORCEADD TAP..6
R 2
(125 1875);
FORCEPROP 3 LASTPIN (75 1875) SIG_NAME M_G_DQ<16>
J 0
(85 1885);
DISPLAY 0.659574 (85 1885);
PAINT MONO (85 1885);
DISPLAY INVISIBLE (85 1885);
FORCEPROP 1 LASTPIN (75 1875) BN 16
J 2
(125 1885);
DISPLAY 0.617021 (125 1885);
PAINT PINK (125 1885);
FORCEPROP 2 LAST CDS_LIB mstr_standard
J 2
(125 1875);
DISPLAY 0.787234 (125 1875);
PAINT MONO (125 1875);
DISPLAY INVISIBLE (125 1875);
FORCEPROP 1 LAST BODY_TYPE PLUMBING
J 2
(125 1825);
DISPLAY 1.234043 (125 1825);
PAINT GREEN (125 1825);
DISPLAY INVISIBLE (125 1825);
FORCEPROP 1 LAST HDL_TAP TRUE
J 2
(-200 1750);
DISPLAY 1.234043 (-200 1750);
PAINT GREEN (-200 1750);
DISPLAY INVISIBLE (-200 1750);
FORCEPROP 1 LAST PATH I77
J 2
(127 1875);
DISPLAY 0.872340 (127 1875);
PAINT GREEN (127 1875);
DISPLAY INVISIBLE (127 1875);
FORCEADD TAP..6
R 2
(125 1975);
FORCEPROP 3 LASTPIN (75 1975) SIG_NAME M_G_DQ<18>
J 0
(85 1985);
DISPLAY 0.659574 (85 1985);
PAINT MONO (85 1985);
DISPLAY INVISIBLE (85 1985);
FORCEPROP 1 LASTPIN (75 1975) BN 18
J 2
(125 1985);
DISPLAY 0.617021 (125 1985);
PAINT PINK (125 1985);
FORCEPROP 2 LAST CDS_LIB mstr_standard
J 2
(125 1975);
DISPLAY 0.787234 (125 1975);
PAINT MONO (125 1975);
DISPLAY INVISIBLE (125 1975);
FORCEPROP 1 LAST BODY_TYPE PLUMBING
J 2
(125 1925);
DISPLAY 1.234043 (125 1925);
PAINT GREEN (125 1925);
DISPLAY INVISIBLE (125 1925);
FORCEPROP 1 LAST HDL_TAP TRUE
J 2
(-200 1850);
DISPLAY 1.234043 (-200 1850);
PAINT GREEN (-200 1850);
DISPLAY INVISIBLE (-200 1850);
FORCEPROP 1 LAST PATH I78
J 2
(127 1975);
DISPLAY 0.872340 (127 1975);
PAINT GREEN (127 1975);
DISPLAY INVISIBLE (127 1975);
FORCEADD TAP..6
R 2
(125 2025);
FORCEPROP 3 LASTPIN (75 2025) SIG_NAME M_G_DQ<19>
J 0
(85 2035);
DISPLAY 0.659574 (85 2035);
PAINT MONO (85 2035);
DISPLAY INVISIBLE (85 2035);
FORCEPROP 1 LASTPIN (75 2025) BN 19
J 2
(125 2035);
DISPLAY 0.617021 (125 2035);
PAINT PINK (125 2035);
FORCEPROP 2 LAST CDS_LIB mstr_standard
J 2
(125 2025);
DISPLAY 0.787234 (125 2025);
PAINT MONO (125 2025);
DISPLAY INVISIBLE (125 2025);
FORCEPROP 1 LAST BODY_TYPE PLUMBING
J 2
(125 1975);
DISPLAY 1.234043 (125 1975);
PAINT GREEN (125 1975);
DISPLAY INVISIBLE (125 1975);
FORCEPROP 1 LAST HDL_TAP TRUE
J 2
(-200 1900);
DISPLAY 1.234043 (-200 1900);
PAINT GREEN (-200 1900);
DISPLAY INVISIBLE (-200 1900);
FORCEPROP 1 LAST PATH I79
J 2
(127 2025);
DISPLAY 0.872340 (127 2025);
PAINT GREEN (127 2025);
DISPLAY INVISIBLE (127 2025);
FORCEADD OFFPAGE..1
(-2025 775);
FORCEPROP 2 LAST $XR0 89 
J 0
(-2246 775);
DISPLAY 0.638298 (-2246 775);
PAINT MONO (-2246 775);
FORCEPROP 2 LAST $XR1 77 
J 0
(-2336 775);
DISPLAY 0.638298 (-2336 775);
PAINT MONO (-2336 775);
FORCEPROP 2 LAST $XR2 79 
J 0
(-2426 775);
DISPLAY 0.638298 (-2426 775);
PAINT MONO (-2426 775);
FORCEPROP 2 LAST $XR3 80 
J 0
(-2516 775);
DISPLAY 0.638298 (-2516 775);
PAINT MONO (-2516 775);
FORCEPROP 2 LAST $XR4 81 
J 0
(-2606 775);
DISPLAY 0.638298 (-2606 775);
PAINT MONO (-2606 775);
FORCEPROP 2 LAST $XR5 82 
J 0
(-2246 739);
DISPLAY 0.638298 (-2246 739);
PAINT MONO (-2246 739);
FORCEPROP 2 LAST CDS_LIB mstr_standard
J 0
(-2025 775);
PAINT ORANGE (-2025 775);
DISPLAY INVISIBLE (-2025 775);
FORCEPROP 1 LAST OFFPAGE TRUE
J 0
(-1700 650);
DISPLAY 0.936170 (-1700 650);
PAINT GREEN (-1700 650);
DISPLAY INVISIBLE (-1700 650);
FORCEPROP 1 LAST COMMENT_BODY TRUE
J 0
(-1900 675);
DISPLAY 0.936170 (-1900 675);
PAINT GREEN (-1900 675);
DISPLAY INVISIBLE (-1900 675);
FORCEPROP 2 LAST PATH I8
J 0
(-2275 825);
DISPLAY 1.021277 (-2275 825);
PAINT ORANGE (-2275 825);
DISPLAY INVISIBLE (-2275 825);
FORCEADD TAP..6
R 2
(125 2075);
FORCEPROP 3 LASTPIN (75 2075) SIG_NAME M_G_DQ<20>
J 0
(85 2085);
DISPLAY 0.659574 (85 2085);
PAINT MONO (85 2085);
DISPLAY INVISIBLE (85 2085);
FORCEPROP 1 LASTPIN (75 2075) BN 20
J 2
(125 2085);
DISPLAY 0.617021 (125 2085);
PAINT PINK (125 2085);
FORCEPROP 2 LAST CDS_LIB mstr_standard
J 2
(125 2075);
DISPLAY 0.787234 (125 2075);
PAINT MONO (125 2075);
DISPLAY INVISIBLE (125 2075);
FORCEPROP 1 LAST BODY_TYPE PLUMBING
J 2
(125 2025);
DISPLAY 1.234043 (125 2025);
PAINT GREEN (125 2025);
DISPLAY INVISIBLE (125 2025);
FORCEPROP 1 LAST HDL_TAP TRUE
J 2
(-200 1950);
DISPLAY 1.234043 (-200 1950);
PAINT GREEN (-200 1950);
DISPLAY INVISIBLE (-200 1950);
FORCEPROP 1 LAST PATH I80
J 2
(127 2075);
DISPLAY 0.872340 (127 2075);
PAINT GREEN (127 2075);
DISPLAY INVISIBLE (127 2075);
FORCEADD TAP..6
R 2
(125 2225);
FORCEPROP 3 LASTPIN (75 2225) SIG_NAME M_G_DQ<23>
J 0
(85 2235);
DISPLAY 0.659574 (85 2235);
PAINT MONO (85 2235);
DISPLAY INVISIBLE (85 2235);
FORCEPROP 1 LASTPIN (75 2225) BN 23
J 2
(125 2235);
DISPLAY 0.617021 (125 2235);
PAINT PINK (125 2235);
FORCEPROP 2 LAST CDS_LIB mstr_standard
J 2
(125 2225);
DISPLAY 0.787234 (125 2225);
PAINT MONO (125 2225);
DISPLAY INVISIBLE (125 2225);
FORCEPROP 1 LAST BODY_TYPE PLUMBING
J 2
(125 2175);
DISPLAY 1.234043 (125 2175);
PAINT GREEN (125 2175);
DISPLAY INVISIBLE (125 2175);
FORCEPROP 1 LAST HDL_TAP TRUE
J 2
(-200 2100);
DISPLAY 1.234043 (-200 2100);
PAINT GREEN (-200 2100);
DISPLAY INVISIBLE (-200 2100);
FORCEPROP 1 LAST PATH I81
J 2
(127 2225);
DISPLAY 0.872340 (127 2225);
PAINT GREEN (127 2225);
DISPLAY INVISIBLE (127 2225);
FORCEADD TAP..6
R 2
(125 2175);
FORCEPROP 3 LASTPIN (75 2175) SIG_NAME M_G_DQ<22>
J 0
(85 2185);
DISPLAY 0.659574 (85 2185);
PAINT MONO (85 2185);
DISPLAY INVISIBLE (85 2185);
FORCEPROP 1 LASTPIN (75 2175) BN 22
J 2
(125 2185);
DISPLAY 0.617021 (125 2185);
PAINT PINK (125 2185);
FORCEPROP 2 LAST CDS_LIB mstr_standard
J 2
(125 2175);
DISPLAY 0.787234 (125 2175);
PAINT MONO (125 2175);
DISPLAY INVISIBLE (125 2175);
FORCEPROP 1 LAST BODY_TYPE PLUMBING
J 2
(125 2125);
DISPLAY 1.234043 (125 2125);
PAINT GREEN (125 2125);
DISPLAY INVISIBLE (125 2125);
FORCEPROP 1 LAST HDL_TAP TRUE
J 2
(-200 2050);
DISPLAY 1.234043 (-200 2050);
PAINT GREEN (-200 2050);
DISPLAY INVISIBLE (-200 2050);
FORCEPROP 1 LAST PATH I82
J 2
(127 2175);
DISPLAY 0.872340 (127 2175);
PAINT GREEN (127 2175);
DISPLAY INVISIBLE (127 2175);
FORCEADD TAP..6
R 2
(125 2125);
FORCEPROP 3 LASTPIN (75 2125) SIG_NAME M_G_DQ<21>
J 0
(85 2135);
DISPLAY 0.659574 (85 2135);
PAINT MONO (85 2135);
DISPLAY INVISIBLE (85 2135);
FORCEPROP 1 LASTPIN (75 2125) BN 21
J 2
(125 2135);
DISPLAY 0.617021 (125 2135);
PAINT PINK (125 2135);
FORCEPROP 2 LAST CDS_LIB mstr_standard
J 2
(125 2125);
DISPLAY 0.787234 (125 2125);
PAINT MONO (125 2125);
DISPLAY INVISIBLE (125 2125);
FORCEPROP 1 LAST BODY_TYPE PLUMBING
J 2
(125 2075);
DISPLAY 1.234043 (125 2075);
PAINT GREEN (125 2075);
DISPLAY INVISIBLE (125 2075);
FORCEPROP 1 LAST HDL_TAP TRUE
J 2
(-200 2000);
DISPLAY 1.234043 (-200 2000);
PAINT GREEN (-200 2000);
DISPLAY INVISIBLE (-200 2000);
FORCEPROP 1 LAST PATH I83
J 2
(127 2125);
DISPLAY 0.872340 (127 2125);
PAINT GREEN (127 2125);
DISPLAY INVISIBLE (127 2125);
FORCEADD TAP..6
R 2
(125 2325);
FORCEPROP 3 LASTPIN (75 2325) SIG_NAME M_G_DQ<25>
J 0
(85 2335);
DISPLAY 0.659574 (85 2335);
PAINT MONO (85 2335);
DISPLAY INVISIBLE (85 2335);
FORCEPROP 1 LASTPIN (75 2325) BN 25
J 2
(125 2335);
DISPLAY 0.617021 (125 2335);
PAINT PINK (125 2335);
FORCEPROP 2 LAST CDS_LIB mstr_standard
J 2
(125 2325);
DISPLAY 0.787234 (125 2325);
PAINT MONO (125 2325);
DISPLAY INVISIBLE (125 2325);
FORCEPROP 1 LAST BODY_TYPE PLUMBING
J 2
(125 2275);
DISPLAY 1.234043 (125 2275);
PAINT GREEN (125 2275);
DISPLAY INVISIBLE (125 2275);
FORCEPROP 1 LAST HDL_TAP TRUE
J 2
(-200 2200);
DISPLAY 1.234043 (-200 2200);
PAINT GREEN (-200 2200);
DISPLAY INVISIBLE (-200 2200);
FORCEPROP 1 LAST PATH I84
J 2
(127 2325);
DISPLAY 0.872340 (127 2325);
PAINT GREEN (127 2325);
DISPLAY INVISIBLE (127 2325);
FORCEADD TAP..6
R 2
(125 2275);
FORCEPROP 3 LASTPIN (75 2275) SIG_NAME M_G_DQ<24>
J 0
(85 2285);
DISPLAY 0.659574 (85 2285);
PAINT MONO (85 2285);
DISPLAY INVISIBLE (85 2285);
FORCEPROP 1 LASTPIN (75 2275) BN 24
J 2
(125 2285);
DISPLAY 0.617021 (125 2285);
PAINT PINK (125 2285);
FORCEPROP 2 LAST CDS_LIB mstr_standard
J 2
(125 2275);
DISPLAY 0.787234 (125 2275);
PAINT MONO (125 2275);
DISPLAY INVISIBLE (125 2275);
FORCEPROP 1 LAST BODY_TYPE PLUMBING
J 2
(125 2225);
DISPLAY 1.234043 (125 2225);
PAINT GREEN (125 2225);
DISPLAY INVISIBLE (125 2225);
FORCEPROP 1 LAST HDL_TAP TRUE
J 2
(-200 2150);
DISPLAY 1.234043 (-200 2150);
PAINT GREEN (-200 2150);
DISPLAY INVISIBLE (-200 2150);
FORCEPROP 1 LAST PATH I85
J 2
(127 2275);
DISPLAY 0.872340 (127 2275);
PAINT GREEN (127 2275);
DISPLAY INVISIBLE (127 2275);
FORCEADD TAP..6
R 2
(125 2475);
FORCEPROP 3 LASTPIN (75 2475) SIG_NAME M_G_DQ<28>
J 0
(85 2485);
DISPLAY 0.659574 (85 2485);
PAINT MONO (85 2485);
DISPLAY INVISIBLE (85 2485);
FORCEPROP 1 LASTPIN (75 2475) BN 28
J 2
(125 2485);
DISPLAY 0.617021 (125 2485);
PAINT PINK (125 2485);
FORCEPROP 2 LAST CDS_LIB mstr_standard
J 2
(125 2475);
DISPLAY 0.787234 (125 2475);
PAINT MONO (125 2475);
DISPLAY INVISIBLE (125 2475);
FORCEPROP 1 LAST BODY_TYPE PLUMBING
J 2
(125 2425);
DISPLAY 1.234043 (125 2425);
PAINT GREEN (125 2425);
DISPLAY INVISIBLE (125 2425);
FORCEPROP 1 LAST HDL_TAP TRUE
J 2
(-200 2350);
DISPLAY 1.234043 (-200 2350);
PAINT GREEN (-200 2350);
DISPLAY INVISIBLE (-200 2350);
FORCEPROP 1 LAST PATH I86
J 2
(127 2475);
DISPLAY 0.872340 (127 2475);
PAINT GREEN (127 2475);
DISPLAY INVISIBLE (127 2475);
FORCEADD TAP..6
R 2
(125 2425);
FORCEPROP 3 LASTPIN (75 2425) SIG_NAME M_G_DQ<27>
J 0
(85 2435);
DISPLAY 0.659574 (85 2435);
PAINT MONO (85 2435);
DISPLAY INVISIBLE (85 2435);
FORCEPROP 1 LASTPIN (75 2425) BN 27
J 2
(125 2435);
DISPLAY 0.617021 (125 2435);
PAINT PINK (125 2435);
FORCEPROP 2 LAST CDS_LIB mstr_standard
J 2
(125 2425);
DISPLAY 0.787234 (125 2425);
PAINT MONO (125 2425);
DISPLAY INVISIBLE (125 2425);
FORCEPROP 1 LAST BODY_TYPE PLUMBING
J 2
(125 2375);
DISPLAY 1.234043 (125 2375);
PAINT GREEN (125 2375);
DISPLAY INVISIBLE (125 2375);
FORCEPROP 1 LAST HDL_TAP TRUE
J 2
(-200 2300);
DISPLAY 1.234043 (-200 2300);
PAINT GREEN (-200 2300);
DISPLAY INVISIBLE (-200 2300);
FORCEPROP 1 LAST PATH I87
J 2
(127 2425);
DISPLAY 0.872340 (127 2425);
PAINT GREEN (127 2425);
DISPLAY INVISIBLE (127 2425);
FORCEADD TAP..6
R 2
(125 2375);
FORCEPROP 3 LASTPIN (75 2375) SIG_NAME M_G_DQ<26>
J 0
(85 2385);
DISPLAY 0.659574 (85 2385);
PAINT MONO (85 2385);
DISPLAY INVISIBLE (85 2385);
FORCEPROP 1 LASTPIN (75 2375) BN 26
J 2
(125 2385);
DISPLAY 0.617021 (125 2385);
PAINT PINK (125 2385);
FORCEPROP 2 LAST CDS_LIB mstr_standard
J 2
(125 2375);
DISPLAY 0.787234 (125 2375);
PAINT MONO (125 2375);
DISPLAY INVISIBLE (125 2375);
FORCEPROP 1 LAST BODY_TYPE PLUMBING
J 2
(125 2325);
DISPLAY 1.234043 (125 2325);
PAINT GREEN (125 2325);
DISPLAY INVISIBLE (125 2325);
FORCEPROP 1 LAST HDL_TAP TRUE
J 2
(-200 2250);
DISPLAY 1.234043 (-200 2250);
PAINT GREEN (-200 2250);
DISPLAY INVISIBLE (-200 2250);
FORCEPROP 1 LAST PATH I88
J 2
(127 2375);
DISPLAY 0.872340 (127 2375);
PAINT GREEN (127 2375);
DISPLAY INVISIBLE (127 2375);
FORCEADD TAP..6
R 2
(125 2525);
FORCEPROP 3 LASTPIN (75 2525) SIG_NAME M_G_DQ<29>
J 0
(85 2535);
DISPLAY 0.659574 (85 2535);
PAINT MONO (85 2535);
DISPLAY INVISIBLE (85 2535);
FORCEPROP 1 LASTPIN (75 2525) BN 29
J 2
(125 2535);
DISPLAY 0.617021 (125 2535);
PAINT PINK (125 2535);
FORCEPROP 2 LAST CDS_LIB mstr_standard
J 2
(125 2525);
DISPLAY 0.787234 (125 2525);
PAINT MONO (125 2525);
DISPLAY INVISIBLE (125 2525);
FORCEPROP 1 LAST BODY_TYPE PLUMBING
J 2
(125 2475);
DISPLAY 1.234043 (125 2475);
PAINT GREEN (125 2475);
DISPLAY INVISIBLE (125 2475);
FORCEPROP 1 LAST HDL_TAP TRUE
J 2
(-200 2400);
DISPLAY 1.234043 (-200 2400);
PAINT GREEN (-200 2400);
DISPLAY INVISIBLE (-200 2400);
FORCEPROP 1 LAST PATH I89
J 2
(127 2525);
DISPLAY 0.872340 (127 2525);
PAINT GREEN (127 2525);
DISPLAY INVISIBLE (127 2525);
FORCEADD OFFPAGE..1
(-2025 1175);
FORCEPROP 2 LAST $XR0 99 
J 0
(-2276 1175);
DISPLAY 0.638298 (-2276 1175);
PAINT MONO (-2276 1175);
FORCEPROP 2 LAST $XR1 77 
J 0
(-2366 1175);
DISPLAY 0.638298 (-2366 1175);
PAINT MONO (-2366 1175);
FORCEPROP 2 LAST $XR2 79 
J 0
(-2456 1175);
DISPLAY 0.638298 (-2456 1175);
PAINT MONO (-2456 1175);
FORCEPROP 2 LAST $XR3 80 
J 0
(-2546 1175);
DISPLAY 0.638298 (-2546 1175);
PAINT MONO (-2546 1175);
FORCEPROP 2 LAST $XR4 81 
J 0
(-2636 1175);
DISPLAY 0.638298 (-2636 1175);
PAINT MONO (-2636 1175);
FORCEPROP 2 LAST $XR5 82 
J 0
(-2726 1175);
DISPLAY 0.638298 (-2726 1175);
PAINT MONO (-2726 1175);
FORCEPROP 2 LAST CDS_LIB mstr_standard
J 0
(-2025 1175);
DISPLAY 0.787234 (-2025 1175);
PAINT MONO (-2025 1175);
DISPLAY INVISIBLE (-2025 1175);
FORCEPROP 1 LAST OFFPAGE TRUE
J 0
(-1700 1050);
DISPLAY 0.936170 (-1700 1050);
PAINT GREEN (-1700 1050);
DISPLAY INVISIBLE (-1700 1050);
FORCEPROP 1 LAST COMMENT_BODY TRUE
J 0
(-1900 1075);
DISPLAY 0.936170 (-1900 1075);
PAINT GREEN (-1900 1075);
DISPLAY INVISIBLE (-1900 1075);
FORCEPROP 2 LAST PATH I9
J 0
(-2275 1225);
DISPLAY 1.021277 (-2275 1225);
PAINT ORANGE (-2275 1225);
DISPLAY INVISIBLE (-2275 1225);
FORCEADD TAP..6
R 2
(125 2575);
FORCEPROP 3 LASTPIN (75 2575) SIG_NAME M_G_DQ<30>
J 0
(85 2585);
DISPLAY 0.659574 (85 2585);
PAINT MONO (85 2585);
DISPLAY INVISIBLE (85 2585);
FORCEPROP 1 LASTPIN (75 2575) BN 30
J 2
(125 2585);
DISPLAY 0.617021 (125 2585);
PAINT PINK (125 2585);
FORCEPROP 2 LAST CDS_LIB mstr_standard
J 2
(125 2575);
DISPLAY 0.787234 (125 2575);
PAINT MONO (125 2575);
DISPLAY INVISIBLE (125 2575);
FORCEPROP 1 LAST BODY_TYPE PLUMBING
J 2
(125 2525);
DISPLAY 1.234043 (125 2525);
PAINT GREEN (125 2525);
DISPLAY INVISIBLE (125 2525);
FORCEPROP 1 LAST HDL_TAP TRUE
J 2
(-200 2450);
DISPLAY 1.234043 (-200 2450);
PAINT GREEN (-200 2450);
DISPLAY INVISIBLE (-200 2450);
FORCEPROP 1 LAST PATH I90
J 2
(127 2575);
DISPLAY 0.872340 (127 2575);
PAINT GREEN (127 2575);
DISPLAY INVISIBLE (127 2575);
FORCEADD TAP..6
R 2
(125 2675);
FORCEPROP 3 LASTPIN (75 2675) SIG_NAME M_G_DQ<32>
J 0
(85 2685);
DISPLAY 0.659574 (85 2685);
PAINT MONO (85 2685);
DISPLAY INVISIBLE (85 2685);
FORCEPROP 1 LASTPIN (75 2675) BN 32
J 2
(125 2685);
DISPLAY 0.617021 (125 2685);
PAINT PINK (125 2685);
FORCEPROP 2 LAST CDS_LIB mstr_standard
J 2
(125 2675);
DISPLAY 0.787234 (125 2675);
PAINT MONO (125 2675);
DISPLAY INVISIBLE (125 2675);
FORCEPROP 1 LAST BODY_TYPE PLUMBING
J 2
(125 2625);
DISPLAY 1.234043 (125 2625);
PAINT GREEN (125 2625);
DISPLAY INVISIBLE (125 2625);
FORCEPROP 1 LAST HDL_TAP TRUE
J 2
(-200 2550);
DISPLAY 1.234043 (-200 2550);
PAINT GREEN (-200 2550);
DISPLAY INVISIBLE (-200 2550);
FORCEPROP 1 LAST PATH I91
J 2
(127 2675);
DISPLAY 0.872340 (127 2675);
PAINT GREEN (127 2675);
DISPLAY INVISIBLE (127 2675);
FORCEADD TAP..6
R 2
(125 2725);
FORCEPROP 3 LASTPIN (75 2725) SIG_NAME M_G_DQ<33>
J 0
(85 2735);
DISPLAY 0.659574 (85 2735);
PAINT MONO (85 2735);
DISPLAY INVISIBLE (85 2735);
FORCEPROP 1 LASTPIN (75 2725) BN 33
J 2
(125 2735);
DISPLAY 0.617021 (125 2735);
PAINT PINK (125 2735);
FORCEPROP 2 LAST CDS_LIB mstr_standard
J 2
(125 2725);
DISPLAY 0.787234 (125 2725);
PAINT MONO (125 2725);
DISPLAY INVISIBLE (125 2725);
FORCEPROP 1 LAST BODY_TYPE PLUMBING
J 2
(125 2675);
DISPLAY 1.234043 (125 2675);
PAINT GREEN (125 2675);
DISPLAY INVISIBLE (125 2675);
FORCEPROP 1 LAST HDL_TAP TRUE
J 2
(-200 2600);
DISPLAY 1.234043 (-200 2600);
PAINT GREEN (-200 2600);
DISPLAY INVISIBLE (-200 2600);
FORCEPROP 1 LAST PATH I92
J 2
(127 2725);
DISPLAY 0.872340 (127 2725);
PAINT GREEN (127 2725);
DISPLAY INVISIBLE (127 2725);
FORCEADD TAP..6
R 2
(125 2625);
FORCEPROP 3 LASTPIN (75 2625) SIG_NAME M_G_DQ<31>
J 0
(85 2635);
DISPLAY 0.659574 (85 2635);
PAINT MONO (85 2635);
DISPLAY INVISIBLE (85 2635);
FORCEPROP 1 LASTPIN (75 2625) BN 31
J 2
(125 2635);
DISPLAY 0.617021 (125 2635);
PAINT PINK (125 2635);
FORCEPROP 2 LAST CDS_LIB mstr_standard
J 2
(125 2625);
DISPLAY 0.787234 (125 2625);
PAINT MONO (125 2625);
DISPLAY INVISIBLE (125 2625);
FORCEPROP 1 LAST BODY_TYPE PLUMBING
J 2
(125 2575);
DISPLAY 1.234043 (125 2575);
PAINT GREEN (125 2575);
DISPLAY INVISIBLE (125 2575);
FORCEPROP 1 LAST HDL_TAP TRUE
J 2
(-200 2500);
DISPLAY 1.234043 (-200 2500);
PAINT GREEN (-200 2500);
DISPLAY INVISIBLE (-200 2500);
FORCEPROP 1 LAST PATH I93
J 2
(127 2625);
DISPLAY 0.872340 (127 2625);
PAINT GREEN (127 2625);
DISPLAY INVISIBLE (127 2625);
FORCEADD TAP..6
R 2
(125 2825);
FORCEPROP 3 LASTPIN (75 2825) SIG_NAME M_G_DQ<35>
J 0
(85 2835);
DISPLAY 0.659574 (85 2835);
PAINT MONO (85 2835);
DISPLAY INVISIBLE (85 2835);
FORCEPROP 1 LASTPIN (75 2825) BN 35
J 2
(125 2835);
DISPLAY 0.617021 (125 2835);
PAINT PINK (125 2835);
FORCEPROP 2 LAST CDS_LIB mstr_standard
J 2
(125 2825);
DISPLAY 0.787234 (125 2825);
PAINT MONO (125 2825);
DISPLAY INVISIBLE (125 2825);
FORCEPROP 1 LAST BODY_TYPE PLUMBING
J 2
(125 2775);
DISPLAY 1.234043 (125 2775);
PAINT GREEN (125 2775);
DISPLAY INVISIBLE (125 2775);
FORCEPROP 1 LAST HDL_TAP TRUE
J 2
(-200 2700);
DISPLAY 1.234043 (-200 2700);
PAINT GREEN (-200 2700);
DISPLAY INVISIBLE (-200 2700);
FORCEPROP 1 LAST PATH I94
J 2
(127 2825);
DISPLAY 0.872340 (127 2825);
PAINT GREEN (127 2825);
DISPLAY INVISIBLE (127 2825);
FORCEADD TAP..6
R 2
(125 2775);
FORCEPROP 3 LASTPIN (75 2775) SIG_NAME M_G_DQ<34>
J 0
(85 2785);
DISPLAY 0.659574 (85 2785);
PAINT MONO (85 2785);
DISPLAY INVISIBLE (85 2785);
FORCEPROP 1 LASTPIN (75 2775) BN 34
J 2
(125 2785);
DISPLAY 0.617021 (125 2785);
PAINT PINK (125 2785);
FORCEPROP 2 LAST CDS_LIB mstr_standard
J 2
(125 2775);
DISPLAY 0.787234 (125 2775);
PAINT MONO (125 2775);
DISPLAY INVISIBLE (125 2775);
FORCEPROP 1 LAST BODY_TYPE PLUMBING
J 2
(125 2725);
DISPLAY 1.234043 (125 2725);
PAINT GREEN (125 2725);
DISPLAY INVISIBLE (125 2725);
FORCEPROP 1 LAST HDL_TAP TRUE
J 2
(-200 2650);
DISPLAY 1.234043 (-200 2650);
PAINT GREEN (-200 2650);
DISPLAY INVISIBLE (-200 2650);
FORCEPROP 1 LAST PATH I95
J 2
(127 2775);
DISPLAY 0.872340 (127 2775);
PAINT GREEN (127 2775);
DISPLAY INVISIBLE (127 2775);
FORCEADD PVDDQ_GHJ..1
(400 2300);
FORCEPROP 3 LASTPIN (400 2250) SIG_NAME PVDDQ_GHJ\g
J 0
(410 2260);
DISPLAY 0.659574 (410 2260);
PAINT MONO (410 2260);
DISPLAY INVISIBLE (410 2260);
FORCEPROP 1 LAST VOLTAGE 1.2V
J 0
(355 2257);
DISPLAY 0.340426 (355 2257);
PAINT SKYBLUE (355 2257);
DISPLAY INVISIBLE (355 2257);
FORCEPROP 2 LAST BOM_COST MEM
J 0
(400 2305);
PAINT ORANGE (400 2305);
DISPLAY INVISIBLE (400 2305);
FORCEPROP 2 LAST CDS_LIB mstr_symbols
J 0
(400 2300);
PAINT ORANGE (400 2300);
DISPLAY INVISIBLE (400 2300);
FORCEPROP 1 LAST BODY_TYPE PLUMBING
J 0
(355 2257);
DISPLAY 0.340426 (355 2257);
PAINT GREEN (355 2257);
DISPLAY INVISIBLE (355 2257);
FORCEPROP 1 LAST PATH I96
J 0
(450 2325);
DISPLAY 0.872340 (450 2325);
PAINT AQUA (450 2325);
DISPLAY INVISIBLE (450 2325);
FORCEPROP 2 LAST ROOM DDR4_GH_G
J 0
(400 2400);
DISPLAY 0.787234 (400 2400);
PAINT ORANGE (400 2400);
DISPLAY INVISIBLE (400 2400);
FORCEPROP 1 LAST HDL_POWER PVDDQ_GHJ
J 1
(400 2350);
DISPLAY 0.872340 (400 2350);
PAINT GREEN (400 2350);
DISPLAY INVISIBLE (400 2350);
FORCEADD PVTT_GHJ..1
(600 2450);
FORCEPROP 3 LASTPIN (600 2400) SIG_NAME PVTT_GHJ\g
J 0
(610 2410);
DISPLAY 0.659574 (610 2410);
PAINT MONO (610 2410);
DISPLAY INVISIBLE (610 2410);
FORCEPROP 1 LAST VOLTAGE 0.6V
J 0
(555 2407);
DISPLAY 0.340426 (555 2407);
PAINT SKYBLUE (555 2407);
DISPLAY INVISIBLE (555 2407);
FORCEPROP 2 LAST BOM_COST MEM
J 0
(600 2455);
PAINT ORANGE (600 2455);
DISPLAY INVISIBLE (600 2455);
FORCEPROP 2 LAST CDS_LIB mstr_symbols
J 0
(600 2450);
PAINT ORANGE (600 2450);
DISPLAY INVISIBLE (600 2450);
FORCEPROP 1 LAST BODY_TYPE PLUMBING
J 0
(555 2407);
DISPLAY 0.340426 (555 2407);
PAINT GREEN (555 2407);
DISPLAY INVISIBLE (555 2407);
FORCEPROP 1 LAST PATH I97
J 0
(650 2475);
DISPLAY 0.872340 (650 2475);
PAINT AQUA (650 2475);
DISPLAY INVISIBLE (650 2475);
FORCEPROP 2 LAST ROOM DDR4_GH_G
J 0
(600 2550);
DISPLAY 0.787234 (600 2550);
PAINT ORANGE (600 2550);
DISPLAY INVISIBLE (600 2550);
FORCEPROP 1 LAST HDL_POWER PVTT_GHJ
J 1
(600 2500);
DISPLAY 0.872340 (600 2500);
PAINT GREEN (600 2500);
DISPLAY INVISIBLE (600 2500);
FORCEADD TAP..6
R 2
(125 2875);
FORCEPROP 3 LASTPIN (75 2875) SIG_NAME M_G_DQ<36>
J 0
(85 2885);
DISPLAY 0.659574 (85 2885);
PAINT MONO (85 2885);
DISPLAY INVISIBLE (85 2885);
FORCEPROP 1 LASTPIN (75 2875) BN 36
J 2
(125 2885);
DISPLAY 0.617021 (125 2885);
PAINT PINK (125 2885);
FORCEPROP 2 LAST CDS_LIB mstr_standard
J 2
(125 2875);
DISPLAY 0.787234 (125 2875);
PAINT MONO (125 2875);
DISPLAY INVISIBLE (125 2875);
FORCEPROP 1 LAST BODY_TYPE PLUMBING
J 2
(125 2825);
DISPLAY 1.234043 (125 2825);
PAINT GREEN (125 2825);
DISPLAY INVISIBLE (125 2825);
FORCEPROP 1 LAST HDL_TAP TRUE
J 2
(-200 2750);
DISPLAY 1.234043 (-200 2750);
PAINT GREEN (-200 2750);
DISPLAY INVISIBLE (-200 2750);
FORCEPROP 1 LAST PATH I98
J 2
(127 2875);
DISPLAY 0.872340 (127 2875);
PAINT GREEN (127 2875);
DISPLAY INVISIBLE (127 2875);
FORCEADD TAP..6
R 2
(125 2975);
FORCEPROP 3 LASTPIN (75 2975) SIG_NAME M_G_DQ<38>
J 0
(85 2985);
DISPLAY 0.659574 (85 2985);
PAINT MONO (85 2985);
DISPLAY INVISIBLE (85 2985);
FORCEPROP 1 LASTPIN (75 2975) BN 38
J 2
(125 2985);
DISPLAY 0.617021 (125 2985);
PAINT PINK (125 2985);
FORCEPROP 2 LAST CDS_LIB mstr_standard
J 2
(125 2975);
DISPLAY 0.787234 (125 2975);
PAINT MONO (125 2975);
DISPLAY INVISIBLE (125 2975);
FORCEPROP 1 LAST BODY_TYPE PLUMBING
J 2
(125 2925);
DISPLAY 1.234043 (125 2925);
PAINT GREEN (125 2925);
DISPLAY INVISIBLE (125 2925);
FORCEPROP 1 LAST HDL_TAP TRUE
J 2
(-200 2850);
DISPLAY 1.234043 (-200 2850);
PAINT GREEN (-200 2850);
DISPLAY INVISIBLE (-200 2850);
FORCEPROP 1 LAST PATH I99
J 2
(127 2975);
DISPLAY 0.872340 (127 2975);
PAINT GREEN (127 2975);
DISPLAY INVISIBLE (127 2975);
FORCEADD BOM_NOTE..1
(-3275 5000);
FORCEPROP 0 LAST L1 UNSTUFF FOR SKU B
J 0
(-3425 4900);
DISPLAY 1.063830 (-3425 4900);
PAINT WHITE (-3425 4900);
FORCEPROP 2 LAST BOM_COST SB
J 0
(-3425 4975);
DISPLAY 1.361702 (-3425 4975);
PAINT ORANGE (-3425 4975);
DISPLAY INVISIBLE (-3425 4975);
FORCEPROP 2 LAST CDS_LIB mstr_symbols
J 0
(-3275 5000);
PAINT ORANGE (-3275 5000);
DISPLAY INVISIBLE (-3275 5000);
FORCEPROP 1 LAST COMMENT_BODY TRUE
J 0
(-3250 5100);
DISPLAY 1.319149 (-3250 5100);
PAINT ORANGE (-3250 5100);
DISPLAY INVISIBLE (-3250 5100);
FORCEPROP 2 LAST ROOM SB_HEADERS
J 0
(-3425 4975);
DISPLAY 1.361702 (-3425 4975);
PAINT ORANGE (-3425 4975);
DISPLAY INVISIBLE (-3425 4975);
FORCEADD INTEL_CORP_BPAGE..1
(4400 200);
FORCEPROP 1 LAST CDS_CON_LAST_MODIFIED Tue Dec 01 11:51:41 2015
J 0
(2975 525);
PAINT ORANGE (2975 525);
DISPLAY INVISIBLE (2975 525);
FORCEPROP 1 LAST CUSTOM_TXT_CDS <CURRENT_DESIGN_SHEET> OF <TOTAL_DESIGN_SHEETS>
J 0
(3900 225);
PAINT GREEN (3900 225);
FORCEPROP 1 LAST CUSTOM_TXT_CDS <CON_LAST_MODIFIED>
J 0
(2475 550);
PAINT GREEN (2475 550);
FORCEPROP 2 LAST CUSTOM_TXT_CDS <XR_PAGE_TITLE>
J 0
(-3490 5450);
DISPLAY 0.638298 (-3490 5450);
PAINT PINK (-3490 5450);
DISPLAY INVISIBLE (-3490 5450);
FORCEPROP 1 LAST SCH_ADDRESS3 Santa Clara, CA 95052-8119
J 0
(425 225);
DISPLAY 0.617021 (425 225);
PAINT GREEN (425 225);
FORCEPROP 1 LAST SCH_ADDRESS2 P.O. BOX 58119
J 0
(425 275);
DISPLAY 0.617021 (425 275);
PAINT GREEN (425 275);
FORCEPROP 1 LAST SCH_ADDRESS1 2200 Mission College Blvd.
J 0
(425 325);
DISPLAY 0.617021 (425 325);
PAINT GREEN (425 325);
FORCEPROP 1 LAST SCH_TITLE CPU1 DDR4 CH G DIMM1
J 0
(-3550 250);
DISPLAY 1.212766 (-3550 250);
PAINT ORANGE (-3550 250);
FORCEPROP 1 LAST SCH_NUMBER H4694802
J 0
(3100 350);
DISPLAY 1.212766 (3100 350);
PAINT YELLOW (3100 350);
FORCEPROP 1 LAST SCH_DEPT BESD
J 1
(-50 300);
DISPLAY 1.212766 (-50 300);
PAINT YELLOW (-50 300);
FORCEPROP 1 LAST SCH_REV 2.420
J 0
(4150 350);
DISPLAY 0.978723 (4150 350);
PAINT YELLOW (4150 350);
FORCEPROP 2 LAST CDS_LIB mstr_symbols
J 0
(4400 200);
PAINT MONO (4400 200);
DISPLAY INVISIBLE (4400 200);
FORCEPROP 2 LAST PAGE_BORDER TRUE
J 0
(-3490 5450);
DISPLAY 0.638298 (-3490 5450);
PAINT PINK (-3490 5450);
DISPLAY INVISIBLE (-3490 5450);
FORCEPROP 1 LAST COMMENT_BODY TRUE
J 0
(4412 212);
DISPLAY 0.468085 (4412 212);
PAINT GREEN (4412 212);
DISPLAY INVISIBLE (4412 212);
FORCEPROP 2 LAST CDS_XR_PAGE_TITLE CR-78 : @BASEBOARD_FAB2_LIB.BASEBOARD_FAB2(SCH_1):PAGE78
J 0
(-3490 5450);
DISPLAY 0.638298 (-3490 5450);
PAINT PINK (-3490 5450);
DISPLAY INVISIBLE (-3490 5450);
WIRE 17 -1 (2700 4825)(2700 4850);
WIRE 17 -1 (2700 4725)(2700 4825);
WIRE 17 -1 (3300 4850)(2700 4850);
FORCEPROP 2 LAST SIG_NAME M_G_DQS_DN<17:0>
J 0
(2725 4860);
DISPLAY 0.617021 (2725 4860);
PAINT ORANGE (2725 4860);
WIRE 17 -1 (2700 4625)(2700 4725);
WIRE 17 -1 (2700 4525)(2700 4625);
WIRE 17 -1 (2700 4425)(2700 4525);
WIRE 17 -1 (2700 4325)(2700 4425);
WIRE 17 -1 (2700 4225)(2700 4325);
WIRE 17 -1 (2700 4125)(2700 4225);
WIRE 17 -1 (2700 4025)(2700 4125);
WIRE 17 -1 (2700 3925)(2700 4025);
WIRE 17 -1 (2700 3825)(2700 3925);
WIRE 17 -1 (2700 3725)(2700 3825);
WIRE 17 -1 (2700 3625)(2700 3725);
WIRE 17 -1 (2700 3525)(2700 3625);
WIRE 17 -1 (2700 3425)(2700 3525);
WIRE 17 -1 (2500 4875)(2500 4900);
WIRE 17 -1 (2500 4775)(2500 4875);
WIRE 17 -1 (3300 4900)(2500 4900);
FORCEPROP 2 LAST SIG_NAME M_G_DQS_DP<17:0>
J 0
(2725 4910);
DISPLAY 0.617021 (2725 4910);
PAINT ORANGE (2725 4910);
WIRE 17 -1 (2500 4675)(2500 4775);
WIRE 17 -1 (2500 4575)(2500 4675);
WIRE 17 -1 (2500 4475)(2500 4575);
WIRE 17 -1 (2500 4375)(2500 4475);
WIRE 17 -1 (2500 4275)(2500 4375);
WIRE 17 -1 (2500 4175)(2500 4275);
WIRE 17 -1 (2500 4075)(2500 4175);
WIRE 17 -1 (2500 3975)(2500 4075);
WIRE 17 -1 (2500 3875)(2500 3975);
WIRE 17 -1 (2500 3775)(2500 3875);
WIRE 17 -1 (2500 3675)(2500 3775);
WIRE 17 -1 (2500 3575)(2500 3675);
WIRE 17 -1 (2500 3475)(2500 3575);
WIRE 17 -1 (2700 3325)(2700 3425);
WIRE 17 -1 (2700 3225)(2700 3325);
WIRE 17 -1 (2700 3125)(2700 3225);
WIRE 17 -1 (2500 3375)(2500 3475);
WIRE 17 -1 (2500 3275)(2500 3375);
WIRE 17 -1 (2500 3175)(2500 3275);
WIRE 17 -1 (175 2450)(175 2500);
WIRE 17 -1 (175 2400)(175 2450);
WIRE 17 -1 (175 2500)(175 2550);
WIRE 17 -1 (175 2550)(175 2600);
WIRE 17 -1 (175 2350)(175 2400);
WIRE 17 -1 (175 2300)(175 2350);
WIRE 17 -1 (175 2600)(175 2650);
WIRE 17 -1 (175 2650)(175 2700);
WIRE 17 -1 (175 2250)(175 2300);
WIRE 17 -1 (175 2200)(175 2250);
WIRE 17 -1 (175 2700)(175 2750);
WIRE 17 -1 (175 2750)(175 2800);
WIRE 17 -1 (175 2150)(175 2200);
WIRE 17 -1 (175 2100)(175 2150);
WIRE 17 -1 (175 2800)(175 2850);
WIRE 17 -1 (175 2850)(175 2900);
WIRE 17 -1 (175 2050)(175 2100);
WIRE 17 -1 (175 2000)(175 2050);
WIRE 17 -1 (175 2900)(175 2950);
WIRE 17 -1 (175 2950)(175 3000);
WIRE 17 -1 (175 1950)(175 2000);
WIRE 17 -1 (175 1900)(175 1950);
WIRE 17 -1 (175 3000)(175 3050);
WIRE 17 -1 (175 3050)(175 3100);
WIRE 17 -1 (175 1850)(175 1900);
WIRE 17 -1 (175 1800)(175 1850);
WIRE 17 -1 (175 3100)(175 3150);
WIRE 17 -1 (175 3150)(175 3200);
WIRE 17 -1 (175 1750)(175 1800);
WIRE 17 -1 (175 1700)(175 1750);
WIRE 17 -1 (175 3200)(175 3250);
WIRE 17 -1 (175 3250)(175 3300);
WIRE 17 -1 (175 1650)(175 1700);
WIRE 17 -1 (175 1600)(175 1650);
WIRE 17 -1 (175 3300)(175 3350);
WIRE 17 -1 (175 3350)(175 3400);
WIRE 17 -1 (175 1550)(175 1600);
WIRE 17 -1 (175 1500)(175 1550);
WIRE 17 -1 (175 3400)(175 3450);
WIRE 17 -1 (175 3450)(175 3500);
WIRE 17 -1 (175 1450)(175 1500);
WIRE 17 -1 (175 1400)(175 1450);
WIRE 17 -1 (175 3500)(175 3550);
WIRE 17 -1 (175 3550)(175 3600);
WIRE 17 -1 (175 1350)(175 1400);
WIRE 17 -1 (175 1300)(175 1350);
WIRE 17 -1 (175 3600)(175 3650);
WIRE 17 -1 (175 3650)(175 3700);
WIRE 17 -1 (175 1250)(175 1300);
WIRE 17 -1 (175 1200)(175 1250);
WIRE 17 -1 (175 3700)(175 3750);
WIRE 17 -1 (175 3750)(175 3800);
WIRE 17 -1 (175 1150)(175 1200);
WIRE 17 -1 (175 1100)(175 1150);
WIRE 17 -1 (175 3800)(175 3850);
WIRE 17 -1 (175 3850)(175 3900);
WIRE 17 -1 (175 3900)(175 3950);
WIRE 17 -1 (175 3950)(175 4000);
WIRE 17 -1 (175 4000)(175 4050);
WIRE 17 -1 (175 4050)(175 4100);
WIRE 17 -1 (175 4100)(175 4150);
WIRE 17 -1 (175 4150)(175 4200);
WIRE 17 -1 (175 4200)(175 4250);
WIRE 17 -1 (175 4275)(175 4250);
WIRE 17 -1 (625 4275)(175 4275);
FORCEPROP 2 LAST SIG_NAME M_G_DQ<63:0>
J 0
(215 4285);
DISPLAY 0.617021 (215 4285);
PAINT ORANGE (215 4285);
WIRE 17 -1 (-1425 4200)(-1425 4250);
WIRE 17 -1 (-1425 4150)(-1425 4200);
WIRE 17 -1 (-1425 4250)(-1425 4275);
WIRE 17 -1 (-1975 4275)(-1425 4275);
FORCEPROP 2 LAST SIG_NAME M_G_MA<17:0>
J 0
(-1950 4285);
DISPLAY 0.617021 (-1950 4285);
PAINT ORANGE (-1950 4285);
WIRE 17 -1 (-1425 4100)(-1425 4150);
WIRE 17 -1 (-1425 4050)(-1425 4100);
WIRE 17 -1 (-1425 4000)(-1425 4050);
WIRE 17 -1 (-1425 3950)(-1425 4000);
WIRE 17 -1 (-1425 3900)(-1425 3950);
WIRE 17 -1 (-1425 3850)(-1425 3900);
WIRE 17 -1 (-1425 3800)(-1425 3850);
WIRE 17 -1 (-1425 3750)(-1425 3800);
WIRE 17 -1 (-1425 3700)(-1425 3750);
WIRE 17 -1 (-1425 3650)(-1425 3700);
WIRE 17 -1 (-1425 3600)(-1425 3650);
WIRE 17 -1 (-1425 3550)(-1425 3600);
WIRE 17 -1 (-1425 3500)(-1425 3550);
WIRE 17 -1 (-1425 3450)(-1425 3500);
WIRE 17 -1 (-1425 3400)(-1425 3450);
WIRE 17 -1 (-1425 3250)(-1425 3300);
WIRE 17 -1 (-1425 3350)(-1425 3300);
WIRE 17 -1 (-1425 3350)(-1975 3350);
FORCEPROP 2 LAST SIG_NAME M_G_BA<1:0>
J 0
(-1950 3360);
DISPLAY 0.617021 (-1950 3360);
PAINT ORANGE (-1950 3360);
WIRE 17 -1 (-1425 3225)(-1425 3200);
WIRE 17 -1 (-1425 3225)(-1975 3225);
FORCEPROP 2 LAST SIG_NAME M_G_BG<1:0>
J 0
(-1950 3235);
DISPLAY 0.617021 (-1950 3235);
PAINT ORANGE (-1950 3235);
WIRE 17 -1 (-1425 3150)(-1425 3200);
WIRE 17 -1 (-1625 3000)(-1625 2900);
WIRE 17 -1 (-1625 3050)(-1625 3000);
WIRE 17 -1 (-1625 3050)(-1975 3050);
FORCEPROP 2 LAST SIG_NAME M_G_CLK_DN<3:0>
J 0
(-1975 3060);
DISPLAY 0.617021 (-1975 3060);
PAINT ORANGE (-1975 3060);
WIRE 17 -1 (-1425 2600)(-1425 2650);
WIRE 17 -1 (-1425 2650)(-1425 2700);
WIRE 17 -1 (-1425 2700)(-1425 2750);
WIRE 17 -1 (-1425 2775)(-1425 2750);
WIRE 17 -1 (-1425 2775)(-1975 2775);
FORCEPROP 2 LAST SIG_NAME M_G_CS_N<7:0>
J 0
(-1950 2785);
DISPLAY 0.617021 (-1950 2785);
PAINT ORANGE (-1950 2785);
WIRE 17 -1 (-1425 3100)(-1425 3050);
WIRE 17 -1 (-1425 3100)(-1975 3100);
FORCEPROP 2 LAST SIG_NAME M_G_CLK_DP<3:0>
J 0
(-1975 3110);
DISPLAY 0.617021 (-1975 3110);
PAINT ORANGE (-1975 3110);
WIRE 17 -1 (-1425 2950)(-1425 3050);
WIRE 17 -1 (-1425 2450)(-1425 2500);
WIRE 17 -1 (-1425 2525)(-1425 2500);
WIRE 17 -1 (-1425 2525)(-1975 2525);
FORCEPROP 2 LAST SIG_NAME M_G_CKE<3:0>
J 0
(-1950 2535);
DISPLAY 0.617021 (-1950 2535);
PAINT ORANGE (-1950 2535);
WIRE 17 -1 (-1425 2375)(-1425 2350);
WIRE 17 -1 (-1425 2375)(-1975 2375);
FORCEPROP 2 LAST SIG_NAME M_G_ODT<3:0>
J 0
(-1950 2385);
DISPLAY 0.617021 (-1950 2385);
PAINT ORANGE (-1950 2385);
WIRE 17 -1 (-1425 2300)(-1425 2350);
WIRE 17 -1 (-1425 2225)(-1425 2200);
WIRE 17 -1 (-1425 2225)(-1975 2225);
FORCEPROP 2 LAST SIG_NAME M_G_ECC<7:0>
J 0
(-1950 2235);
DISPLAY 0.617021 (-1950 2235);
PAINT ORANGE (-1950 2235);
WIRE 17 -1 (-1425 2100)(-1425 2150);
WIRE 17 -1 (-1425 2050)(-1425 2100);
WIRE 17 -1 (-1425 2150)(-1425 2200);
WIRE 17 -1 (-1425 2000)(-1425 2050);
WIRE 17 -1 (-1425 1950)(-1425 2000);
WIRE 17 -1 (-1425 1850)(-1425 1900);
WIRE 17 -1 (-1425 1900)(-1425 1950);
WIRE 16 -1 (-2675 775)(-2675 675);
WIRE 16 -1 (750 2400)(950 2400);
WIRE 16 -1 (750 2400)(750 2450);
WIRE 16 -1 (750 2450)(950 2450);
WIRE 16 -1 (750 2450)(750 2500);
WIRE 16 -1 (750 2500)(950 2500);
WIRE 16 -1 (750 2500)(750 2550);
WIRE 16 -1 (750 2550)(750 2600);
WIRE 16 -1 (750 2550)(950 2550);
WIRE 16 -1 (750 2600)(950 2600);
WIRE 16 -1 (750 2700)(750 2600);
WIRE 16 -1 (2850 3150)(3050 3150);
WIRE 16 -1 (2850 3100)(2850 3150);
WIRE 16 -1 (2850 3100)(3050 3100);
WIRE 16 -1 (2850 3050)(2850 3100);
WIRE 16 -1 (2850 3050)(3050 3050);
WIRE 16 -1 (2850 3000)(2850 3050);
WIRE 16 -1 (2850 3000)(3050 3000);
WIRE 16 -1 (2850 2950)(2850 3000);
WIRE 16 -1 (2850 2950)(3050 2950);
WIRE 16 -1 (2850 2900)(2850 2950);
WIRE 16 -1 (2850 2900)(3050 2900);
WIRE 16 -1 (2850 2850)(2850 2900);
WIRE 16 -1 (2850 2850)(3050 2850);
WIRE 16 -1 (2850 2800)(2850 2850);
WIRE 16 -1 (2850 2800)(3050 2800);
WIRE 16 -1 (2850 2750)(2850 2800);
WIRE 16 -1 (2850 2750)(3050 2750);
WIRE 16 -1 (2850 2700)(2850 2750);
WIRE 16 -1 (2850 2700)(3050 2700);
WIRE 16 -1 (2850 2650)(2850 2700);
WIRE 16 -1 (2850 2650)(3050 2650);
WIRE 16 -1 (2850 2600)(2850 2650);
WIRE 16 -1 (2850 2600)(3050 2600);
WIRE 16 -1 (2850 2550)(2850 2600);
WIRE 16 -1 (2850 2550)(3050 2550);
WIRE 16 -1 (2850 2500)(2850 2550);
WIRE 16 -1 (2850 2500)(3050 2500);
WIRE 16 -1 (2850 2450)(2850 2500);
WIRE 16 -1 (2850 2450)(3050 2450);
WIRE 16 -1 (2850 2400)(2850 2450);
WIRE 16 -1 (2850 2400)(3050 2400);
WIRE 16 -1 (2850 2350)(2850 2400);
WIRE 16 -1 (2850 2350)(3050 2350);
WIRE 16 -1 (2850 2300)(2850 2350);
WIRE 16 -1 (2850 2300)(3050 2300);
WIRE 16 -1 (2850 2250)(2850 2300);
WIRE 16 -1 (2850 2250)(3050 2250);
WIRE 16 -1 (2850 2200)(2850 2250);
WIRE 16 -1 (2850 2200)(3050 2200);
WIRE 16 -1 (2850 2150)(2850 2200);
WIRE 16 -1 (2850 2150)(3050 2150);
WIRE 16 -1 (2850 2100)(2850 2150);
WIRE 16 -1 (2850 2100)(3050 2100);
WIRE 16 -1 (2850 2050)(2850 2100);
WIRE 16 -1 (2850 2050)(3050 2050);
WIRE 16 -1 (2850 2000)(2850 2050);
WIRE 16 -1 (2850 2000)(3050 2000);
WIRE 16 -1 (2850 1950)(2850 2000);
WIRE 16 -1 (2850 1950)(3050 1950);
WIRE 16 -1 (2850 1900)(2850 1950);
WIRE 16 -1 (2850 1900)(3050 1900);
WIRE 16 -1 (2850 1850)(2850 1900);
WIRE 16 -1 (2850 1850)(3050 1850);
WIRE 16 -1 (2850 1800)(2850 1850);
WIRE 16 -1 (2850 1800)(3050 1800);
WIRE 16 -1 (2850 1750)(2850 1800);
WIRE 16 -1 (2850 1750)(3050 1750);
WIRE 16 -1 (2850 1700)(2850 1750);
WIRE 16 -1 (2850 1700)(3050 1700);
WIRE 16 -1 (2850 1650)(2850 1700);
WIRE 16 -1 (2850 1650)(3050 1650);
WIRE 16 -1 (2850 1600)(2850 1650);
WIRE 16 -1 (2850 1600)(3050 1600);
WIRE 16 -1 (2850 1550)(2850 1600);
WIRE 16 -1 (2850 1550)(3050 1550);
WIRE 16 -1 (2850 1500)(2850 1550);
WIRE 16 -1 (2850 1500)(3050 1500);
WIRE 16 -1 (2850 1450)(2850 1500);
WIRE 16 -1 (2850 1450)(3050 1450);
WIRE 16 -1 (2850 1400)(2850 1450);
WIRE 16 -1 (2850 1400)(3050 1400);
WIRE 16 -1 (2850 1350)(2850 1400);
WIRE 16 -1 (2850 1350)(3050 1350);
WIRE 16 -1 (2850 1300)(2850 1350);
WIRE 16 -1 (2850 1300)(3050 1300);
WIRE 16 -1 (2850 1250)(2850 1300);
WIRE 16 -1 (2850 1250)(3050 1250);
WIRE 16 -1 (2850 1200)(2850 1250);
WIRE 16 -1 (2850 1200)(3050 1200);
WIRE 16 -1 (2850 1150)(2850 1200);
WIRE 16 -1 (2850 1150)(3050 1150);
WIRE 16 -1 (2850 1100)(2850 1150);
WIRE 16 -1 (2850 1100)(3050 1100);
WIRE 16 -1 (2850 1050)(2850 1100);
WIRE 16 -1 (2850 1050)(3050 1050);
WIRE 16 -1 (2850 1000)(2850 1050);
WIRE 16 -1 (2850 1000)(3050 1000);
WIRE 16 -1 (2850 950)(2850 1000);
WIRE 16 -1 (2850 950)(3050 950);
WIRE 16 -1 (2850 900)(2850 950);
WIRE 16 -1 (2850 900)(3050 900);
WIRE 16 -1 (2850 850)(2850 900);
WIRE 16 -1 (2850 850)(3050 850);
WIRE 16 -1 (2850 750)(2850 850);
WIRE 16 -1 (4250 3100)(4250 3150);
WIRE 16 -1 (4250 3050)(4250 3100);
WIRE 16 -1 (4250 3100)(4050 3100);
WIRE 16 -1 (4250 3150)(4050 3150);
WIRE 16 -1 (4250 3000)(4250 3050);
WIRE 16 -1 (4250 3050)(4050 3050);
WIRE 16 -1 (4250 2950)(4250 3000);
WIRE 16 -1 (4250 3000)(4050 3000);
WIRE 16 -1 (4250 2900)(4250 2950);
WIRE 16 -1 (4250 2950)(4050 2950);
WIRE 16 -1 (4250 2850)(4250 2900);
WIRE 16 -1 (4250 2900)(4050 2900);
WIRE 16 -1 (4250 2800)(4250 2850);
WIRE 16 -1 (4250 2850)(4050 2850);
WIRE 16 -1 (4250 2750)(4250 2800);
WIRE 16 -1 (4250 2800)(4050 2800);
WIRE 16 -1 (4250 2700)(4250 2750);
WIRE 16 -1 (4250 2750)(4050 2750);
WIRE 16 -1 (4250 2650)(4250 2700);
WIRE 16 -1 (4250 2700)(4050 2700);
WIRE 16 -1 (4250 2600)(4250 2650);
WIRE 16 -1 (4250 2650)(4050 2650);
WIRE 16 -1 (4250 2550)(4250 2600);
WIRE 16 -1 (4250 2600)(4050 2600);
WIRE 16 -1 (4250 2500)(4250 2550);
WIRE 16 -1 (4250 2550)(4050 2550);
WIRE 16 -1 (4250 2450)(4250 2500);
WIRE 16 -1 (4250 2500)(4050 2500);
WIRE 16 -1 (4250 2400)(4250 2450);
WIRE 16 -1 (4250 2450)(4050 2450);
WIRE 16 -1 (4250 2350)(4250 2400);
WIRE 16 -1 (4250 2400)(4050 2400);
WIRE 16 -1 (4250 2300)(4250 2350);
WIRE 16 -1 (4250 2350)(4050 2350);
WIRE 16 -1 (4250 2250)(4250 2300);
WIRE 16 -1 (4250 2300)(4050 2300);
WIRE 16 -1 (4250 2200)(4250 2250);
WIRE 16 -1 (4250 2250)(4050 2250);
WIRE 16 -1 (4250 2150)(4250 2200);
WIRE 16 -1 (4250 2200)(4050 2200);
WIRE 16 -1 (4250 2100)(4250 2150);
WIRE 16 -1 (4250 2150)(4050 2150);
WIRE 16 -1 (4250 2050)(4250 2100);
WIRE 16 -1 (4250 2100)(4050 2100);
WIRE 16 -1 (4250 2000)(4250 2050);
WIRE 16 -1 (4250 2050)(4050 2050);
WIRE 16 -1 (4250 1950)(4250 2000);
WIRE 16 -1 (4250 2000)(4050 2000);
WIRE 16 -1 (4250 1900)(4250 1950);
WIRE 16 -1 (4250 1950)(4050 1950);
WIRE 16 -1 (4250 1850)(4250 1900);
WIRE 16 -1 (4250 1900)(4050 1900);
WIRE 16 -1 (4250 1800)(4250 1850);
WIRE 16 -1 (4250 1850)(4050 1850);
WIRE 16 -1 (4250 1750)(4250 1800);
WIRE 16 -1 (4250 1800)(4050 1800);
WIRE 16 -1 (4250 1700)(4250 1750);
WIRE 16 -1 (4250 1750)(4050 1750);
WIRE 16 -1 (4250 1650)(4250 1700);
WIRE 16 -1 (4250 1700)(4050 1700);
WIRE 16 -1 (4250 1600)(4250 1650);
WIRE 16 -1 (4250 1650)(4050 1650);
WIRE 16 -1 (4250 1550)(4250 1600);
WIRE 16 -1 (4250 1600)(4050 1600);
WIRE 16 -1 (4250 1500)(4250 1550);
WIRE 16 -1 (4250 1550)(4050 1550);
WIRE 16 -1 (4250 1450)(4250 1500);
WIRE 16 -1 (4250 1500)(4050 1500);
WIRE 16 -1 (4250 1400)(4250 1450);
WIRE 16 -1 (4250 1450)(4050 1450);
WIRE 16 -1 (4250 1350)(4250 1400);
WIRE 16 -1 (4250 1400)(4050 1400);
WIRE 16 -1 (4250 1300)(4250 1350);
WIRE 16 -1 (4250 1350)(4050 1350);
WIRE 16 -1 (4250 1250)(4250 1300);
WIRE 16 -1 (4250 1300)(4050 1300);
WIRE 16 -1 (4250 1200)(4250 1250);
WIRE 16 -1 (4250 1250)(4050 1250);
WIRE 16 -1 (4250 1150)(4250 1200);
WIRE 16 -1 (4250 1200)(4050 1200);
WIRE 16 -1 (4250 1100)(4250 1150);
WIRE 16 -1 (4250 1150)(4050 1150);
WIRE 16 -1 (4250 1050)(4250 1100);
WIRE 16 -1 (4250 1100)(4050 1100);
WIRE 16 -1 (4250 1000)(4250 1050);
WIRE 16 -1 (4250 1050)(4050 1050);
WIRE 16 -1 (4250 950)(4250 1000);
WIRE 16 -1 (4250 1000)(4050 1000);
WIRE 16 -1 (4250 900)(4250 950);
WIRE 16 -1 (4250 950)(4050 950);
WIRE 16 -1 (4250 850)(4250 900);
WIRE 16 -1 (4250 900)(4050 900);
WIRE 16 -1 (4250 750)(4250 850);
WIRE 16 -1 (4250 850)(4050 850);
WIRE 16 -1 (1950 2550)(2150 2550);
WIRE 16 -1 (2150 2550)(2150 2600);
WIRE 16 -1 (1950 2600)(2150 2600);
WIRE 16 -1 (2150 2600)(2150 2675);
WIRE 16 -1 (-1350 1325)(-1125 1325);
WIRE 16 -1 (-1350 1375)(-1350 1325);
WIRE 16 -1 (-1350 1375)(-1125 1375);
WIRE 16 -1 (-3325 1375)(-1350 1375);
WIRE 16 -1 (-3325 1375)(-3325 1275);
WIRE 16 -1 (-1125 1275)(-1425 1275);
WIRE 16 -1 (-1425 1425)(-1425 1275);
WIRE 16 -1 (-1125 1425)(-1425 1425);
WIRE 16 -1 (-1425 1425)(-3325 1425);
WIRE 16 -1 (-3325 1525)(-3325 1425);
WIRE 16 -1 (750 900)(950 900);
WIRE 16 -1 (750 900)(750 950);
WIRE 16 -1 (750 950)(950 950);
WIRE 16 -1 (750 950)(750 1000);
WIRE 16 -1 (750 1000)(750 1050);
WIRE 16 -1 (750 1000)(950 1000);
WIRE 16 -1 (750 1050)(950 1050);
WIRE 16 -1 (750 1050)(750 1100);
WIRE 16 -1 (750 1100)(950 1100);
WIRE 16 -1 (750 1100)(750 1150);
WIRE 16 -1 (750 1150)(950 1150);
WIRE 16 -1 (750 1150)(750 1200);
WIRE 16 -1 (750 1200)(950 1200);
WIRE 16 -1 (750 1200)(750 1250);
WIRE 16 -1 (750 1250)(950 1250);
WIRE 16 -1 (750 1250)(750 1300);
WIRE 16 -1 (750 1300)(950 1300);
WIRE 16 -1 (750 1300)(750 1350);
WIRE 16 -1 (750 1350)(950 1350);
WIRE 16 -1 (750 1350)(750 1400);
WIRE 16 -1 (750 1400)(950 1400);
WIRE 16 -1 (750 1400)(750 1450);
WIRE 16 -1 (750 1450)(950 1450);
WIRE 16 -1 (750 1450)(750 1500);
WIRE 16 -1 (750 1500)(750 1550);
WIRE 16 -1 (750 1500)(950 1500);
WIRE 16 -1 (750 1550)(950 1550);
WIRE 16 -1 (750 1550)(750 1600);
WIRE 16 -1 (750 1600)(950 1600);
WIRE 16 -1 (750 1600)(750 1650);
WIRE 16 -1 (750 1650)(950 1650);
WIRE 16 -1 (750 1650)(750 1700);
WIRE 16 -1 (750 1700)(950 1700);
WIRE 16 -1 (750 1700)(750 1750);
WIRE 16 -1 (750 1750)(950 1750);
WIRE 16 -1 (750 1750)(750 1800);
WIRE 16 -1 (750 1800)(950 1800);
WIRE 16 -1 (750 1800)(750 1850);
WIRE 16 -1 (750 1850)(950 1850);
WIRE 16 -1 (750 1850)(750 1900);
WIRE 16 -1 (750 1900)(950 1900);
WIRE 16 -1 (750 1900)(750 1950);
WIRE 16 -1 (750 1950)(950 1950);
WIRE 16 -1 (750 1950)(750 2000);
WIRE 16 -1 (750 2000)(750 2050);
WIRE 16 -1 (750 2000)(950 2000);
WIRE 16 -1 (750 2050)(950 2050);
WIRE 16 -1 (750 2050)(750 2100);
WIRE 16 -1 (750 2100)(950 2100);
WIRE 16 -1 (750 2100)(750 2150);
WIRE 16 -1 (750 2150)(950 2150);
WIRE 16 -1 (400 2150)(750 2150);
WIRE 16 -1 (400 2250)(400 2150);
WIRE 16 -1 (750 2250)(950 2250);
WIRE 16 -1 (750 2250)(750 2300);
WIRE 16 -1 (750 2300)(950 2300);
WIRE 16 -1 (600 2300)(750 2300);
WIRE 16 -1 (600 2400)(600 2300);
WIRE 16 -1 (-1125 1075)(-2675 1075);
FORCEPROP 2 LAST SIG_NAME M_G_VREF
J 0
(-2425 1085);
DISPLAY 0.617021 (-2425 1085);
PAINT ORANGE (-2425 1085);
WIRE 16 -1 (-2775 1075)(-2675 1075);
WIRE 16 -1 (-2675 1075)(-2675 975);
WIRE 16 -1 (-1125 1525)(-2125 1525);
FORCEPROP 2 LAST SIG_NAME M_G_ACT_N
J 0
(-2075 1535);
DISPLAY 0.617021 (-2075 1535);
PAINT ORANGE (-2075 1535);
WIRE 16 -1 (-1125 1575)(-2150 1575);
FORCEPROP 2 LAST SIG_NAME M_G_ALERT_N
J 0
(-2100 1585);
DISPLAY 0.617021 (-2100 1585);
PAINT ORANGE (-2100 1585);
WIRE 16 -1 (-1975 975)(-1125 975);
FORCEPROP 2 LAST SIG_NAME TP_CH_G_DIMM0_RFU_2
J 0
(-1925 985);
DISPLAY 0.617021 (-1925 985);
PAINT ORANGE (-1925 985);
FORCEPROP 2 LASTPROP $XRERR UNIQUE?
J 0
(-2215 975);
DISPLAY 0.638298 (-2215 975);
PAINT MONO (-2215 975);
DISPLAY INVISIBLE (-2215 975);
WIRE 16 -1 (-1975 875)(-1125 875);
FORCEPROP 2 LAST SIG_NAME TP_CH_G_DIMM0_RFU_0
J 0
(-1925 885);
DISPLAY 0.617021 (-1925 885);
PAINT ORANGE (-1925 885);
FORCEPROP 2 LASTPROP $XRERR UNIQUE?
J 0
(-2215 875);
DISPLAY 0.638298 (-2215 875);
PAINT MONO (-2215 875);
DISPLAY INVISIBLE (-2215 875);
WIRE 16 -1 (-1975 925)(-1125 925);
FORCEPROP 2 LAST SIG_NAME TP_CH_G_DIMM0_RFU_1
J 0
(-1925 935);
DISPLAY 0.617021 (-1925 935);
PAINT ORANGE (-1925 935);
FORCEPROP 2 LASTPROP $XRERR UNIQUE?
J 0
(-2215 925);
DISPLAY 0.638298 (-2215 925);
PAINT MONO (-2215 925);
DISPLAY INVISIBLE (-2215 925);
WIRE 16 -1 (-1975 775)(-1125 775);
FORCEPROP 2 LAST SIG_NAME FM_ADR_COMPLETE_GHJ_N
J 0
(-1925 785);
DISPLAY 0.617021 (-1925 785);
PAINT ORANGE (-1925 785);
WIRE 16 -1 (-1575 1625)(-1125 1625);
WIRE 16 -1 (-1575 1625)(-1575 1875);
WIRE 16 -1 (-1575 1875)(-2300 1875);
FORCEPROP 2 LAST SIG_NAME FM_DIMM_EVENT_COD_N
J 0
(-2260 1889);
DISPLAY 0.617021 (-2260 1889);
PAINT ORANGE (-2260 1889);
WIRE 16 -1 (-1975 1225)(-1125 1225);
WIRE 16 -1 (-1975 1175)(-1125 1175);
FORCEPROP 2 LAST SIG_NAME SMB_DDR_GHJ_VPP_SCL
J 0
(-1935 1185);
DISPLAY 0.617021 (-1935 1185);
PAINT ORANGE (-1935 1185);
WIRE 16 -1 (-1125 2025)(-1325 2025);
WIRE 16 -1 (-1125 1975)(-1325 1975);
WIRE 16 -1 (-1125 1925)(-1325 1925);
WIRE 16 -1 (-1125 1875)(-1325 1875);
WIRE 16 -1 (-1125 1825)(-1325 1825);
WIRE 16 -1 (-1475 2175)(-1975 2175);
FORCEPROP 2 LAST SIG_NAME M_G_PAR
J 0
(-1950 2185);
DISPLAY 0.617021 (-1950 2185);
PAINT ORANGE (-1950 2185);
WIRE 16 -1 (-1475 1725)(-1475 2175);
WIRE 16 -1 (-1125 1725)(-1475 1725);
WIRE 16 -1 (-1525 2125)(-1975 2125);
FORCEPROP 2 LAST SIG_NAME M_GHJ_RST_N
J 0
(-1950 2135);
DISPLAY 0.617021 (-1950 2135);
PAINT ORANGE (-1950 2135);
WIRE 16 -1 (-1525 1675)(-1525 2125);
WIRE 16 -1 (-1125 1675)(-1525 1675);
WIRE 16 -1 (-1125 2125)(-1325 2125);
WIRE 16 -1 (-1125 2075)(-1325 2075);
WIRE 16 -1 (-1125 2175)(-1325 2175);
WIRE 16 -1 (-1125 2275)(-1325 2275);
WIRE 16 -1 (-1125 2325)(-1325 2325);
WIRE 16 -1 (-1125 2475)(-1325 2475);
WIRE 16 -1 (-1125 2425)(-1325 2425);
WIRE 16 -1 (-1125 2975)(-1525 2975);
WIRE 16 -1 (-1125 2925)(-1325 2925);
WIRE 16 -1 (-1125 2725)(-1325 2725);
WIRE 16 -1 (-1125 3025)(-1325 3025);
WIRE 16 -1 (-1125 2675)(-1325 2675);
WIRE 16 -1 (-1125 2625)(-1325 2625);
WIRE 16 -1 (-1125 2575)(-1325 2575);
WIRE 16 -1 (-1125 2875)(-1525 2875);
WIRE 16 -1 (-1275 2825)(-1275 2775);
WIRE 16 -1 (-1275 2825)(-1975 2825);
FORCEPROP 2 LAST SIG_NAME M_G_C<2>
J 0
(-1950 2835);
DISPLAY 0.617021 (-1950 2835);
PAINT ORANGE (-1950 2835);
WIRE 16 -1 (-1275 2775)(-1125 2775);
WIRE 16 -1 (-1125 3275)(-1325 3275);
WIRE 16 -1 (-1125 3375)(-1325 3375);
WIRE 16 -1 (-1125 3425)(-1325 3425);
WIRE 16 -1 (-1125 3525)(-1325 3525);
WIRE 16 -1 (-1125 3575)(-1325 3575);
WIRE 16 -1 (-1125 3125)(-1325 3125);
WIRE 16 -1 (-1125 3175)(-1325 3175);
WIRE 16 -1 (-1125 3225)(-1325 3225);
WIRE 16 -1 (-1125 3475)(-1325 3475);
WIRE 16 -1 (-1125 3975)(-1325 3975);
WIRE 16 -1 (-1125 4025)(-1325 4025);
WIRE 16 -1 (-1125 3625)(-1325 3625);
WIRE 16 -1 (-1125 3675)(-1325 3675);
WIRE 16 -1 (-1125 3725)(-1325 3725);
WIRE 16 -1 (-1125 3775)(-1325 3775);
WIRE 16 -1 (-1125 3825)(-1325 3825);
WIRE 16 -1 (-1125 3875)(-1325 3875);
WIRE 16 -1 (-1125 3925)(-1325 3925);
WIRE 16 -1 (-1125 4075)(-1325 4075);
WIRE 16 -1 (-1125 4225)(-1325 4225);
WIRE 16 -1 (-1125 4125)(-1325 4125);
WIRE 16 -1 (-1125 4175)(-1325 4175);
WIRE 16 -1 (75 4225)(-125 4225);
WIRE 16 -1 (75 2525)(-125 2525);
WIRE 16 -1 (75 2475)(-125 2475);
WIRE 16 -1 (75 4175)(-125 4175);
WIRE 16 -1 (75 4125)(-125 4125);
WIRE 16 -1 (75 4075)(-125 4075);
WIRE 16 -1 (75 4025)(-125 4025);
WIRE 16 -1 (75 3875)(-125 3875);
WIRE 16 -1 (75 3825)(-125 3825);
WIRE 16 -1 (75 3375)(-125 3375);
WIRE 16 -1 (75 3325)(-125 3325);
WIRE 16 -1 (75 3275)(-125 3275);
WIRE 16 -1 (75 3225)(-125 3225);
WIRE 16 -1 (75 3175)(-125 3175);
WIRE 16 -1 (75 3125)(-125 3125);
WIRE 16 -1 (75 3075)(-125 3075);
WIRE 16 -1 (75 3025)(-125 3025);
WIRE 16 -1 (75 2925)(-125 2925);
WIRE 16 -1 (75 2775)(-125 2775);
WIRE 16 -1 (75 2725)(-125 2725);
WIRE 16 -1 (75 2675)(-125 2675);
WIRE 16 -1 (75 2625)(-125 2625);
WIRE 16 -1 (75 2575)(-125 2575);
WIRE 16 -1 (75 2325)(-125 2325);
WIRE 16 -1 (75 2275)(-125 2275);
WIRE 16 -1 (75 2225)(-125 2225);
WIRE 16 -1 (75 2175)(-125 2175);
WIRE 16 -1 (75 2125)(-125 2125);
WIRE 16 -1 (75 2075)(-125 2075);
WIRE 16 -1 (75 2025)(-125 2025);
WIRE 16 -1 (75 1975)(-125 1975);
WIRE 16 -1 (75 1875)(-125 1875);
WIRE 16 -1 (75 1775)(-125 1775);
WIRE 16 -1 (75 1725)(-125 1725);
WIRE 16 -1 (75 1675)(-125 1675);
WIRE 16 -1 (75 1625)(-125 1625);
WIRE 16 -1 (75 1525)(-125 1525);
WIRE 16 -1 (75 1425)(-125 1425);
WIRE 16 -1 (75 1375)(-125 1375);
WIRE 16 -1 (75 1125)(-125 1125);
WIRE 16 -1 (75 1075)(-125 1075);
WIRE 16 -1 (75 2825)(-125 2825);
WIRE 16 -1 (75 2875)(-125 2875);
WIRE 16 -1 (75 2975)(-125 2975);
WIRE 16 -1 (75 2375)(-125 2375);
WIRE 16 -1 (75 1825)(-125 1825);
WIRE 16 -1 (75 1925)(-125 1925);
WIRE 16 -1 (75 3925)(-125 3925);
WIRE 16 -1 (75 3975)(-125 3975);
WIRE 16 -1 (75 3775)(-125 3775);
WIRE 16 -1 (75 3725)(-125 3725);
WIRE 16 -1 (75 3675)(-125 3675);
WIRE 16 -1 (75 3625)(-125 3625);
WIRE 16 -1 (75 3575)(-125 3575);
WIRE 16 -1 (75 3525)(-125 3525);
WIRE 16 -1 (75 3475)(-125 3475);
WIRE 16 -1 (75 3425)(-125 3425);
WIRE 16 -1 (75 1175)(-125 1175);
WIRE 16 -1 (75 1225)(-125 1225);
WIRE 16 -1 (75 1275)(-125 1275);
WIRE 16 -1 (75 1325)(-125 1325);
WIRE 16 -1 (75 1575)(-125 1575);
WIRE 16 -1 (75 1475)(-125 1475);
WIRE 16 -1 (75 2425)(-125 2425);
WIRE 16 -1 (2400 3150)(2200 3150);
WIRE 16 -1 (2400 3250)(2200 3250);
WIRE 16 -1 (2400 3350)(2200 3350);
WIRE 16 -1 (2400 3450)(2200 3450);
WIRE 16 -1 (2400 3550)(2200 3550);
WIRE 16 -1 (2400 3650)(2200 3650);
WIRE 16 -1 (2400 3750)(2200 3750);
WIRE 16 -1 (2400 3850)(2200 3850);
WIRE 16 -1 (2400 3950)(2200 3950);
WIRE 16 -1 (2400 4050)(2200 4050);
WIRE 16 -1 (2600 3100)(2200 3100);
WIRE 16 -1 (2600 3200)(2200 3200);
WIRE 16 -1 (2600 3300)(2200 3300);
WIRE 16 -1 (2600 3400)(2200 3400);
WIRE 16 -1 (2600 3500)(2200 3500);
WIRE 16 -1 (2600 3600)(2200 3600);
WIRE 16 -1 (2600 3700)(2200 3700);
WIRE 16 -1 (2600 3800)(2200 3800);
WIRE 16 -1 (2600 3900)(2200 3900);
WIRE 16 -1 (2600 4000)(2200 4000);
WIRE 16 -1 (2400 4150)(2200 4150);
WIRE 16 -1 (2400 4250)(2200 4250);
WIRE 16 -1 (2400 4350)(2200 4350);
WIRE 16 -1 (2400 4450)(2200 4450);
WIRE 16 -1 (2400 4550)(2200 4550);
WIRE 16 -1 (2400 4650)(2200 4650);
WIRE 16 -1 (2400 4750)(2200 4750);
WIRE 16 -1 (2400 4850)(2200 4850);
WIRE 16 -1 (2600 4100)(2200 4100);
WIRE 16 -1 (2600 4200)(2200 4200);
WIRE 16 -1 (2600 4300)(2200 4300);
WIRE 16 -1 (2600 4400)(2200 4400);
WIRE 16 -1 (2600 4500)(2200 4500);
WIRE 16 -1 (2600 4600)(2200 4600);
WIRE 16 -1 (2600 4700)(2200 4700);
WIRE 16 -1 (2600 4800)(2200 4800);
DOT 1 (4250 3100);
DOT 1 (4250 3050);
DOT 1 (4250 2900);
DOT 1 (4250 2950);
DOT 1 (4250 3000);
DOT 1 (4250 2800);
DOT 1 (4250 2850);
DOT 1 (4250 2750);
DOT 1 (4250 2700);
DOT 1 (4250 2650);
DOT 1 (4250 2550);
DOT 1 (4250 2600);
DOT 1 (4250 2500);
DOT 1 (4250 2400);
DOT 1 (4250 2450);
DOT 1 (4250 2250);
DOT 1 (4250 2300);
DOT 1 (4250 2350);
DOT 1 (4250 2200);
DOT 1 (4250 2150);
DOT 1 (4250 2000);
DOT 1 (4250 2050);
DOT 1 (4250 2100);
DOT 1 (4250 1900);
DOT 1 (4250 1950);
DOT 1 (4250 1850);
DOT 1 (4250 1800);
DOT 1 (4250 1750);
DOT 1 (4250 1650);
DOT 1 (4250 1700);
DOT 1 (4250 1600);
DOT 1 (4250 1550);
DOT 1 (4250 1500);
DOT 1 (4250 1350);
DOT 1 (4250 1400);
DOT 1 (4250 1450);
DOT 1 (4250 1300);
DOT 1 (4250 1250);
DOT 1 (4250 1100);
DOT 1 (4250 1150);
DOT 1 (4250 1200);
DOT 1 (4250 1050);
DOT 1 (4250 1000);
DOT 1 (4250 950);
DOT 1 (4250 850);
DOT 1 (4250 900);
DOT 1 (2850 3050);
DOT 1 (2850 3000);
DOT 1 (2850 2950);
DOT 1 (2850 2900);
DOT 1 (2850 2800);
DOT 1 (2850 2850);
DOT 1 (2850 2750);
DOT 1 (2850 2650);
DOT 1 (2850 2700);
DOT 1 (2850 2550);
DOT 1 (2850 2600);
DOT 1 (2850 2500);
DOT 1 (2850 2450);
DOT 1 (2850 2400);
DOT 1 (2850 2250);
DOT 1 (2850 2300);
DOT 1 (2850 2350);
DOT 1 (2850 2150);
DOT 1 (2850 2200);
DOT 1 (2850 2000);
DOT 1 (2850 2050);
DOT 1 (2850 2100);
DOT 1 (2850 1900);
DOT 1 (2850 1950);
DOT 1 (2150 2600);
DOT 1 (2850 1850);
DOT 1 (2850 1800);
DOT 1 (2850 1750);
DOT 1 (2850 1650);
DOT 1 (2850 1700);
DOT 1 (2850 1600);
DOT 1 (2850 1500);
DOT 1 (2850 1550);
DOT 1 (2850 1350);
DOT 1 (2850 1400);
DOT 1 (2850 1450);
DOT 1 (2850 1250);
DOT 1 (2850 1300);
DOT 1 (2850 1100);
DOT 1 (2850 1150);
DOT 1 (2850 1200);
DOT 1 (2850 1000);
DOT 1 (2850 1050);
DOT 1 (2850 850);
DOT 1 (2850 900);
DOT 1 (2850 950);
DOT 1 (750 2600);
DOT 1 (750 2550);
DOT 1 (750 2500);
DOT 1 (750 2300);
DOT 1 (750 2050);
DOT 1 (750 2000);
DOT 1 (750 1950);
DOT 1 (750 1900);
DOT 1 (750 1850);
DOT 1 (750 1750);
DOT 1 (750 1800);
DOT 1 (750 1700);
DOT 1 (750 1650);
DOT 1 (750 1600);
DOT 1 (750 1550);
DOT 1 (750 1500);
DOT 1 (750 1450);
DOT 1 (750 1350);
DOT 1 (750 1400);
DOT 1 (750 1250);
DOT 1 (750 1300);
DOT 1 (750 1200);
DOT 1 (750 1150);
DOT 1 (750 1100);
DOT 1 (750 1050);
DOT 1 (750 950);
DOT 1 (-2675 1075);
DOT 1 (-1425 1425);
DOT 1 (-1350 1375);
DOT 1 (2850 3100);
DOT 1 (750 1000);
DOT 1 (750 2100);
DOT 1 (750 2150);
DOT 1 (750 2450);
FORCENOTE
PLACE CAP NEAR DIMM CONNECTOR
(-2938 527) 0;
DISPLAY LEFT (-2938 527);
DISPLAY 1.574468 (-2938 527);
PAINT PURPLE (-2938 527);
FORCENOTE
SMBUS ADDR: 0XA2
(-3550 400) 0;
DISPLAY LEFT (-3550 400);
DISPLAY 1.574468 (-3550 400);
PAINT PURPLE (-3550 400);
QUIT
